FILE_TYPE = MACRO_DRAWING;
SET COLOR_WIRE YELLOW;
SET COLOR_PROP MONO;
SET COLOR_DOT WHITE;
SET COLOR_ARC YELLOW;
SET COLOR_BODY GREEN;
SET COLOR_NOTE MONO;
SET PROP_DISPLAY VALUE;
SET PAGE_NUMBER P43;
FORCEADD SCONN288_H44441004..1
(-2400 2750);
FORCEPROP 1 LAST LOCATION J4G1
J 0
(-2850 4650);
DISPLAY 0.617021 (-2850 4650);
PAINT AQUA (-2850 4650);
FORCEPROP 1 LAST PART_NUMBER H44441-004
J 0
(-2850 750);
DISPLAY 0.617021 (-2850 750);
PAINT BLUE (-2850 750);
FORCEPROP 1 LAST MATERIAL SCONN
J 0
(-2850 4600);
DISPLAY 0.617021 (-2850 4600);
PAINT SKYBLUE (-2850 4600);
FORCEPROP 2 LASTPIN (-2900 1250) $PN 146
J 2
(-2910 1260);
DISPLAY 0.617021 (-2910 1260);
PAINT ORANGE (-2910 1260);
FORCEPROP 2 LASTPIN (-2900 1600) $PN 284
J 2
(-2910 1610);
DISPLAY 0.617021 (-2910 1610);
PAINT ORANGE (-2910 1610);
FORCEPROP 2 LASTPIN (-2900 1400) $PN 285
J 2
(-2910 1410);
DISPLAY 0.617021 (-2910 1410);
PAINT ORANGE (-2910 1410);
FORCEPROP 2 LASTPIN (-2900 1350) $PN 141
J 2
(-2910 1360);
DISPLAY 0.617021 (-2910 1360);
PAINT ORANGE (-2910 1360);
FORCEPROP 2 LASTPIN (-2900 950) $PN 230
J 2
(-2910 960);
DISPLAY 0.617021 (-2910 960);
PAINT ORANGE (-2910 960);
FORCEPROP 2 LASTPIN (-2900 1550) $PN 238
J 2
(-2910 1560);
DISPLAY 0.617021 (-2910 1560);
PAINT ORANGE (-2910 1560);
FORCEPROP 2 LASTPIN (-2900 1500) $PN 140
J 2
(-2910 1510);
DISPLAY 0.617021 (-2910 1510);
PAINT ORANGE (-2910 1510);
FORCEPROP 2 LASTPIN (-2900 1450) $PN 139
J 2
(-2910 1460);
DISPLAY 0.617021 (-2910 1460);
PAINT ORANGE (-2910 1460);
FORCEPROP 2 LASTPIN (-2900 2900) $PN 237
J 2
(-2910 2910);
DISPLAY 0.617021 (-2910 2910);
PAINT ORANGE (-2910 2910);
FORCEPROP 2 LASTPIN (-2900 2850) $PN 93
J 2
(-2910 2860);
DISPLAY 0.617021 (-2910 2860);
PAINT ORANGE (-2910 2860);
FORCEPROP 2 LASTPIN (-2900 2800) $PN 89
J 2
(-2910 2810);
DISPLAY 0.617021 (-2910 2810);
PAINT ORANGE (-2910 2810);
FORCEPROP 2 LASTPIN (-2900 2750) $PN 84
J 2
(-2910 2760);
DISPLAY 0.617021 (-2910 2760);
PAINT ORANGE (-2910 2760);
FORCEPROP 2 LASTPIN (-2900 1150) $PN 144
J 2
(-2910 1160);
DISPLAY 0.617021 (-2910 1160);
PAINT ORANGE (-2910 1160);
FORCEPROP 2 LASTPIN (-2900 1100) $PN 227
J 2
(-2910 1110);
DISPLAY 0.617021 (-2910 1110);
PAINT ORANGE (-2910 1110);
FORCEPROP 2 LASTPIN (-2900 1050) $PN 205
J 2
(-2910 1060);
DISPLAY 0.617021 (-2910 1060);
PAINT ORANGE (-2910 1060);
FORCEPROP 2 LASTPIN (-2900 1850) $PN 58
J 2
(-2910 1860);
DISPLAY 0.617021 (-2910 1860);
PAINT ORANGE (-2910 1860);
FORCEPROP 2 LASTPIN (-2900 1900) $PN 222
J 2
(-2910 1910);
DISPLAY 0.617021 (-2910 1910);
PAINT ORANGE (-2910 1910);
FORCEPROP 2 LASTPIN (-2900 2500) $PN 91
J 2
(-2910 2510);
DISPLAY 0.617021 (-2910 2510);
PAINT ORANGE (-2910 2510);
FORCEPROP 2 LASTPIN (-2900 2450) $PN 87
J 2
(-2910 2460);
DISPLAY 0.617021 (-2910 2460);
PAINT ORANGE (-2910 2460);
FORCEPROP 2 LASTPIN (-2900 1800) $PN 78
J 2
(-2910 1810);
DISPLAY 0.617021 (-2910 1810);
PAINT ORANGE (-2910 1810);
FORCEPROP 2 LASTPIN (-1900 4400) $PN 280
J 0
(-1890 4410);
DISPLAY 0.617021 (-1890 4410);
PAINT ORANGE (-1890 4410);
FORCEPROP 2 LASTPIN (-1900 4350) $PN 135
J 0
(-1890 4360);
DISPLAY 0.617021 (-1890 4360);
PAINT ORANGE (-1890 4360);
FORCEPROP 2 LASTPIN (-1900 4300) $PN 273
J 0
(-1890 4310);
DISPLAY 0.617021 (-1890 4310);
PAINT ORANGE (-1890 4310);
FORCEPROP 2 LASTPIN (-1900 4250) $PN 128
J 0
(-1890 4260);
DISPLAY 0.617021 (-1890 4260);
PAINT ORANGE (-1890 4260);
FORCEPROP 2 LASTPIN (-1900 4200) $PN 282
J 0
(-1890 4210);
DISPLAY 0.617021 (-1890 4210);
PAINT ORANGE (-1890 4210);
FORCEPROP 2 LASTPIN (-1900 4150) $PN 137
J 0
(-1890 4160);
DISPLAY 0.617021 (-1890 4160);
PAINT ORANGE (-1890 4160);
FORCEPROP 2 LASTPIN (-1900 4100) $PN 275
J 0
(-1890 4110);
DISPLAY 0.617021 (-1890 4110);
PAINT ORANGE (-1890 4110);
FORCEPROP 2 LASTPIN (-1900 4050) $PN 130
J 0
(-1890 4060);
DISPLAY 0.617021 (-1890 4060);
PAINT ORANGE (-1890 4060);
FORCEPROP 2 LASTPIN (-1900 4000) $PN 269
J 0
(-1890 4010);
DISPLAY 0.617021 (-1890 4010);
PAINT ORANGE (-1890 4010);
FORCEPROP 2 LASTPIN (-1900 3950) $PN 124
J 0
(-1890 3960);
DISPLAY 0.617021 (-1890 3960);
PAINT ORANGE (-1890 3960);
FORCEPROP 2 LASTPIN (-1900 3900) $PN 262
J 0
(-1890 3910);
DISPLAY 0.617021 (-1890 3910);
PAINT ORANGE (-1890 3910);
FORCEPROP 2 LASTPIN (-1900 3850) $PN 117
J 0
(-1890 3860);
DISPLAY 0.617021 (-1890 3860);
PAINT ORANGE (-1890 3860);
FORCEPROP 2 LASTPIN (-1900 3800) $PN 271
J 0
(-1890 3810);
DISPLAY 0.617021 (-1890 3810);
PAINT ORANGE (-1890 3810);
FORCEPROP 2 LASTPIN (-1900 3750) $PN 126
J 0
(-1890 3760);
DISPLAY 0.617021 (-1890 3760);
PAINT ORANGE (-1890 3760);
FORCEPROP 2 LASTPIN (-1900 3700) $PN 264
J 0
(-1890 3710);
DISPLAY 0.617021 (-1890 3710);
PAINT ORANGE (-1890 3710);
FORCEPROP 2 LASTPIN (-1900 3650) $PN 119
J 0
(-1890 3660);
DISPLAY 0.617021 (-1890 3660);
PAINT ORANGE (-1890 3660);
FORCEPROP 2 LASTPIN (-1900 3600) $PN 258
J 0
(-1890 3610);
DISPLAY 0.617021 (-1890 3610);
PAINT ORANGE (-1890 3610);
FORCEPROP 2 LASTPIN (-1900 3550) $PN 113
J 0
(-1890 3560);
DISPLAY 0.617021 (-1890 3560);
PAINT ORANGE (-1890 3560);
FORCEPROP 2 LASTPIN (-1900 3500) $PN 251
J 0
(-1890 3510);
DISPLAY 0.617021 (-1890 3510);
PAINT ORANGE (-1890 3510);
FORCEPROP 2 LASTPIN (-1900 3450) $PN 106
J 0
(-1890 3460);
DISPLAY 0.617021 (-1890 3460);
PAINT ORANGE (-1890 3460);
FORCEPROP 2 LASTPIN (-1900 3400) $PN 260
J 0
(-1890 3410);
DISPLAY 0.617021 (-1890 3410);
PAINT ORANGE (-1890 3410);
FORCEPROP 2 LASTPIN (-1900 3350) $PN 115
J 0
(-1890 3360);
DISPLAY 0.617021 (-1890 3360);
PAINT ORANGE (-1890 3360);
FORCEPROP 2 LASTPIN (-1900 3300) $PN 253
J 0
(-1890 3310);
DISPLAY 0.617021 (-1890 3310);
PAINT ORANGE (-1890 3310);
FORCEPROP 2 LASTPIN (-1900 3250) $PN 108
J 0
(-1890 3260);
DISPLAY 0.617021 (-1890 3260);
PAINT ORANGE (-1890 3260);
FORCEPROP 2 LASTPIN (-1900 3200) $PN 247
J 0
(-1890 3210);
DISPLAY 0.617021 (-1890 3210);
PAINT ORANGE (-1890 3210);
FORCEPROP 2 LASTPIN (-1900 3150) $PN 102
J 0
(-1890 3160);
DISPLAY 0.617021 (-1890 3160);
PAINT ORANGE (-1890 3160);
FORCEPROP 2 LASTPIN (-1900 3100) $PN 240
J 0
(-1890 3110);
DISPLAY 0.617021 (-1890 3110);
PAINT ORANGE (-1890 3110);
FORCEPROP 2 LASTPIN (-1900 3050) $PN 95
J 0
(-1890 3060);
DISPLAY 0.617021 (-1890 3060);
PAINT ORANGE (-1890 3060);
FORCEPROP 2 LASTPIN (-1900 3000) $PN 249
J 0
(-1890 3010);
DISPLAY 0.617021 (-1890 3010);
PAINT ORANGE (-1890 3010);
FORCEPROP 2 LASTPIN (-1900 2950) $PN 104
J 0
(-1890 2960);
DISPLAY 0.617021 (-1890 2960);
PAINT ORANGE (-1890 2960);
FORCEPROP 2 LASTPIN (-1900 2900) $PN 242
J 0
(-1890 2910);
DISPLAY 0.617021 (-1890 2910);
PAINT ORANGE (-1890 2910);
FORCEPROP 2 LASTPIN (-1900 2850) $PN 97
J 0
(-1890 2860);
DISPLAY 0.617021 (-1890 2860);
PAINT ORANGE (-1890 2860);
FORCEPROP 2 LASTPIN (-1900 2800) $PN 188
J 0
(-1890 2810);
DISPLAY 0.617021 (-1890 2810);
PAINT ORANGE (-1890 2810);
FORCEPROP 2 LASTPIN (-1900 2750) $PN 43
J 0
(-1890 2760);
DISPLAY 0.617021 (-1890 2760);
PAINT ORANGE (-1890 2760);
FORCEPROP 2 LASTPIN (-1900 2700) $PN 181
J 0
(-1890 2710);
DISPLAY 0.617021 (-1890 2710);
PAINT ORANGE (-1890 2710);
FORCEPROP 2 LASTPIN (-1900 2650) $PN 36
J 0
(-1890 2660);
DISPLAY 0.617021 (-1890 2660);
PAINT ORANGE (-1890 2660);
FORCEPROP 2 LASTPIN (-1900 2600) $PN 190
J 0
(-1890 2610);
DISPLAY 0.617021 (-1890 2610);
PAINT ORANGE (-1890 2610);
FORCEPROP 2 LASTPIN (-1900 2550) $PN 45
J 0
(-1890 2560);
DISPLAY 0.617021 (-1890 2560);
PAINT ORANGE (-1890 2560);
FORCEPROP 2 LASTPIN (-1900 2500) $PN 183
J 0
(-1890 2510);
DISPLAY 0.617021 (-1890 2510);
PAINT ORANGE (-1890 2510);
FORCEPROP 2 LASTPIN (-1900 2450) $PN 38
J 0
(-1890 2460);
DISPLAY 0.617021 (-1890 2460);
PAINT ORANGE (-1890 2460);
FORCEPROP 2 LASTPIN (-1900 2400) $PN 177
J 0
(-1890 2410);
DISPLAY 0.617021 (-1890 2410);
PAINT ORANGE (-1890 2410);
FORCEPROP 2 LASTPIN (-1900 2350) $PN 32
J 0
(-1890 2360);
DISPLAY 0.617021 (-1890 2360);
PAINT ORANGE (-1890 2360);
FORCEPROP 2 LASTPIN (-1900 2300) $PN 170
J 0
(-1890 2310);
DISPLAY 0.617021 (-1890 2310);
PAINT ORANGE (-1890 2310);
FORCEPROP 2 LASTPIN (-1900 2250) $PN 25
J 0
(-1890 2260);
DISPLAY 0.617021 (-1890 2260);
PAINT ORANGE (-1890 2260);
FORCEPROP 2 LASTPIN (-1900 2200) $PN 179
J 0
(-1890 2210);
DISPLAY 0.617021 (-1890 2210);
PAINT ORANGE (-1890 2210);
FORCEPROP 2 LASTPIN (-1900 2150) $PN 34
J 0
(-1890 2160);
DISPLAY 0.617021 (-1890 2160);
PAINT ORANGE (-1890 2160);
FORCEPROP 2 LASTPIN (-1900 2100) $PN 172
J 0
(-1890 2110);
DISPLAY 0.617021 (-1890 2110);
PAINT ORANGE (-1890 2110);
FORCEPROP 2 LASTPIN (-1900 2050) $PN 27
J 0
(-1890 2060);
DISPLAY 0.617021 (-1890 2060);
PAINT ORANGE (-1890 2060);
FORCEPROP 2 LASTPIN (-1900 2000) $PN 166
J 0
(-1890 2010);
DISPLAY 0.617021 (-1890 2010);
PAINT ORANGE (-1890 2010);
FORCEPROP 2 LASTPIN (-1900 1950) $PN 21
J 0
(-1890 1960);
DISPLAY 0.617021 (-1890 1960);
PAINT ORANGE (-1890 1960);
FORCEPROP 2 LASTPIN (-1900 1900) $PN 159
J 0
(-1890 1910);
DISPLAY 0.617021 (-1890 1910);
PAINT ORANGE (-1890 1910);
FORCEPROP 2 LASTPIN (-1900 1850) $PN 14
J 0
(-1890 1860);
DISPLAY 0.617021 (-1890 1860);
PAINT ORANGE (-1890 1860);
FORCEPROP 2 LASTPIN (-1900 1800) $PN 168
J 0
(-1890 1810);
DISPLAY 0.617021 (-1890 1810);
PAINT ORANGE (-1890 1810);
FORCEPROP 2 LASTPIN (-1900 1750) $PN 23
J 0
(-1890 1760);
DISPLAY 0.617021 (-1890 1760);
PAINT ORANGE (-1890 1760);
FORCEPROP 2 LASTPIN (-1900 1700) $PN 161
J 0
(-1890 1710);
DISPLAY 0.617021 (-1890 1710);
PAINT ORANGE (-1890 1710);
FORCEPROP 2 LASTPIN (-1900 1650) $PN 16
J 0
(-1890 1660);
DISPLAY 0.617021 (-1890 1660);
PAINT ORANGE (-1890 1660);
FORCEPROP 2 LASTPIN (-1900 1600) $PN 155
J 0
(-1890 1610);
DISPLAY 0.617021 (-1890 1610);
PAINT ORANGE (-1890 1610);
FORCEPROP 2 LASTPIN (-1900 1550) $PN 10
J 0
(-1890 1560);
DISPLAY 0.617021 (-1890 1560);
PAINT ORANGE (-1890 1560);
FORCEPROP 2 LASTPIN (-1900 1500) $PN 148
J 0
(-1890 1510);
DISPLAY 0.617021 (-1890 1510);
PAINT ORANGE (-1890 1510);
FORCEPROP 2 LASTPIN (-1900 1450) $PN 3
J 0
(-1890 1460);
DISPLAY 0.617021 (-1890 1460);
PAINT ORANGE (-1890 1460);
FORCEPROP 2 LASTPIN (-1900 1400) $PN 157
J 0
(-1890 1410);
DISPLAY 0.617021 (-1890 1410);
PAINT ORANGE (-1890 1410);
FORCEPROP 2 LASTPIN (-1900 1350) $PN 12
J 0
(-1890 1360);
DISPLAY 0.617021 (-1890 1360);
PAINT ORANGE (-1890 1360);
FORCEPROP 2 LASTPIN (-1900 1300) $PN 150
J 0
(-1890 1310);
DISPLAY 0.617021 (-1890 1310);
PAINT ORANGE (-1890 1310);
FORCEPROP 2 LASTPIN (-1900 1250) $PN 5
J 0
(-1890 1260);
DISPLAY 0.617021 (-1890 1260);
PAINT ORANGE (-1890 1260);
FORCEPROP 2 LASTPIN (-2900 2650) $PN 203
J 2
(-2910 2660);
DISPLAY 0.617021 (-2910 2660);
PAINT ORANGE (-2910 2660);
FORCEPROP 2 LASTPIN (-2900 2600) $PN 60
J 2
(-2910 2610);
DISPLAY 0.617021 (-2910 2610);
PAINT ORANGE (-2910 2610);
FORCEPROP 2 LASTPIN (-2900 3200) $PN 218
J 2
(-2910 3210);
DISPLAY 0.617021 (-2910 3210);
PAINT ORANGE (-2910 3210);
FORCEPROP 2 LASTPIN (-2900 3150) $PN 219
J 2
(-2910 3160);
DISPLAY 0.617021 (-2910 3160);
PAINT ORANGE (-2910 3160);
FORCEPROP 2 LASTPIN (-2900 3100) $PN 74
J 2
(-2910 3110);
DISPLAY 0.617021 (-2910 3110);
PAINT ORANGE (-2910 3110);
FORCEPROP 2 LASTPIN (-2900 3050) $PN 75
J 2
(-2910 3060);
DISPLAY 0.617021 (-2910 3060);
PAINT ORANGE (-2910 3060);
FORCEPROP 2 LASTPIN (-2900 2350) $PN 199
J 2
(-2910 2360);
DISPLAY 0.617021 (-2910 2360);
PAINT ORANGE (-2910 2360);
FORCEPROP 2 LASTPIN (-2900 2300) $PN 54
J 2
(-2910 2310);
DISPLAY 0.617021 (-2910 2310);
PAINT ORANGE (-2910 2310);
FORCEPROP 2 LASTPIN (-2900 2250) $PN 192
J 2
(-2910 2260);
DISPLAY 0.617021 (-2910 2260);
PAINT ORANGE (-2910 2260);
FORCEPROP 2 LASTPIN (-2900 2200) $PN 47
J 2
(-2910 2210);
DISPLAY 0.617021 (-2910 2210);
PAINT ORANGE (-2910 2210);
FORCEPROP 2 LASTPIN (-2900 2150) $PN 201
J 2
(-2910 2160);
DISPLAY 0.617021 (-2910 2160);
PAINT ORANGE (-2910 2160);
FORCEPROP 2 LASTPIN (-2900 2100) $PN 56
J 2
(-2910 2110);
DISPLAY 0.617021 (-2910 2110);
PAINT ORANGE (-2910 2110);
FORCEPROP 2 LASTPIN (-2900 2050) $PN 194
J 2
(-2910 2060);
DISPLAY 0.617021 (-2910 2060);
PAINT ORANGE (-2910 2060);
FORCEPROP 2 LASTPIN (-2900 2000) $PN 49
J 2
(-2910 2010);
DISPLAY 0.617021 (-2910 2010);
PAINT ORANGE (-2910 2010);
FORCEPROP 2 LASTPIN (-2900 2950) $PN 235
J 2
(-2910 2960);
DISPLAY 0.617021 (-2910 2960);
PAINT ORANGE (-2910 2960);
FORCEPROP 2 LASTPIN (-2900 3350) $PN 207
J 2
(-2910 3360);
DISPLAY 0.617021 (-2910 3360);
PAINT ORANGE (-2910 3360);
FORCEPROP 2 LASTPIN (-2900 3300) $PN 63
J 2
(-2910 3310);
DISPLAY 0.617021 (-2910 3310);
PAINT ORANGE (-2910 3310);
FORCEPROP 2 LASTPIN (-2900 3450) $PN 224
J 2
(-2910 3460);
DISPLAY 0.617021 (-2910 3460);
PAINT ORANGE (-2910 3460);
FORCEPROP 2 LASTPIN (-2900 3400) $PN 81
J 2
(-2910 3410);
DISPLAY 0.617021 (-2910 3410);
PAINT ORANGE (-2910 3410);
FORCEPROP 2 LASTPIN (-2900 1750) $PN 208
J 2
(-2910 1760);
DISPLAY 0.617021 (-2910 1760);
PAINT ORANGE (-2910 1760);
FORCEPROP 2 LASTPIN (-2900 1700) $PN 62
J 2
(-2910 1710);
DISPLAY 0.617021 (-2910 1710);
PAINT ORANGE (-2910 1710);
FORCEPROP 2 LASTPIN (-2900 4400) $PN 234
J 2
(-2910 4410);
DISPLAY 0.617021 (-2910 4410);
PAINT ORANGE (-2910 4410);
FORCEPROP 2 LASTPIN (-2900 4350) $PN 82
J 2
(-2910 4360);
DISPLAY 0.617021 (-2910 4360);
PAINT ORANGE (-2910 4360);
FORCEPROP 2 LASTPIN (-2900 4300) $PN 86
J 2
(-2910 4310);
DISPLAY 0.617021 (-2910 4310);
PAINT ORANGE (-2910 4310);
FORCEPROP 2 LASTPIN (-2900 4250) $PN 228
J 2
(-2910 4260);
DISPLAY 0.617021 (-2910 4260);
PAINT ORANGE (-2910 4260);
FORCEPROP 2 LASTPIN (-2900 4200) $PN 232
J 2
(-2910 4210);
DISPLAY 0.617021 (-2910 4210);
PAINT ORANGE (-2910 4210);
FORCEPROP 2 LASTPIN (-2900 4150) $PN 65
J 2
(-2910 4160);
DISPLAY 0.617021 (-2910 4160);
PAINT ORANGE (-2910 4160);
FORCEPROP 2 LASTPIN (-2900 4100) $PN 210
J 2
(-2910 4110);
DISPLAY 0.617021 (-2910 4110);
PAINT ORANGE (-2910 4110);
FORCEPROP 2 LASTPIN (-2900 4050) $PN 225
J 2
(-2910 4060);
DISPLAY 0.617021 (-2910 4060);
PAINT ORANGE (-2910 4060);
FORCEPROP 2 LASTPIN (-2900 4000) $PN 66
J 2
(-2910 4010);
DISPLAY 0.617021 (-2910 4010);
PAINT ORANGE (-2910 4010);
FORCEPROP 2 LASTPIN (-2900 3950) $PN 68
J 2
(-2910 3960);
DISPLAY 0.617021 (-2910 3960);
PAINT ORANGE (-2910 3960);
FORCEPROP 2 LASTPIN (-2900 3900) $PN 211
J 2
(-2910 3910);
DISPLAY 0.617021 (-2910 3910);
PAINT ORANGE (-2910 3910);
FORCEPROP 2 LASTPIN (-2900 3850) $PN 69
J 2
(-2910 3860);
DISPLAY 0.617021 (-2910 3860);
PAINT ORANGE (-2910 3860);
FORCEPROP 2 LASTPIN (-2900 3800) $PN 213
J 2
(-2910 3810);
DISPLAY 0.617021 (-2910 3810);
PAINT ORANGE (-2910 3810);
FORCEPROP 2 LASTPIN (-2900 3750) $PN 214
J 2
(-2910 3760);
DISPLAY 0.617021 (-2910 3760);
PAINT ORANGE (-2910 3760);
FORCEPROP 2 LASTPIN (-2900 3700) $PN 71
J 2
(-2910 3710);
DISPLAY 0.617021 (-2910 3710);
PAINT ORANGE (-2910 3710);
FORCEPROP 2 LASTPIN (-2900 3650) $PN 216
J 2
(-2910 3660);
DISPLAY 0.617021 (-2910 3660);
PAINT ORANGE (-2910 3660);
FORCEPROP 2 LASTPIN (-2900 3600) $PN 72
J 2
(-2910 3610);
DISPLAY 0.617021 (-2910 3610);
PAINT ORANGE (-2910 3610);
FORCEPROP 2 LASTPIN (-2900 3550) $PN 79
J 2
(-2910 3560);
DISPLAY 0.617021 (-2910 3560);
PAINT ORANGE (-2910 3560);
FORCEPROP 1 LAST PACK_TYPE PIP
J 0
(-2850 4700);
PAINT SKYBLUE (-2850 4700);
DISPLAY INVISIBLE (-2850 4700);
FORCEPROP 2 LAST BOM_COST MEM
J 0
(-2400 2750);
PAINT ORANGE (-2400 2750);
DISPLAY INVISIBLE (-2400 2750);
FORCEPROP 2 LAST CDS_LIB mstr_sconn
J 0
(-2400 2750);
PAINT ORANGE (-2400 2750);
DISPLAY INVISIBLE (-2400 2750);
FORCEPROP 2 LAST SEC_TYPE PIP
J 0
(-2850 4700);
DISPLAY 1.021277 (-2850 4700);
PAINT ORANGE (-2850 4700);
DISPLAY INVISIBLE (-2850 4700);
FORCEPROP 2 LAST SEC 1
J 0
(-2850 4700);
DISPLAY 0.680851 (-2850 4700);
PAINT MONO (-2850 4700);
DISPLAY INVISIBLE (-2850 4700);
FORCEPROP 2 LAST CDS_LOCATION J4G1
J 0
(-2850 4650);
DISPLAY 0.617021 (-2850 4650);
PAINT AQUA (-2850 4650);
DISPLAY INVISIBLE (-2850 4650);
FORCEPROP 1 LAST PATH I1
J 0
(-2400 4600);
PAINT GREEN (-2400 4600);
DISPLAY INVISIBLE (-2400 4600);
FORCEPROP 2 LAST ROOM DDR4_CH_A
J 0
(-2400 2750);
PAINT ORANGE (-2400 2750);
DISPLAY INVISIBLE (-2400 2750);
FORCEADD TAP..6
R 2
(-1600 4100);
FORCEPROP 3 LASTPIN (-1650 4100) SIG_NAME M_A_DQ<56>
J 0
(-1640 4110);
DISPLAY 0.659574 (-1640 4110);
PAINT MONO (-1640 4110);
DISPLAY INVISIBLE (-1640 4110);
FORCEPROP 1 LASTPIN (-1650 4100) BN 56
J 2
(-1600 4110);
DISPLAY 0.617021 (-1600 4110);
PAINT PINK (-1600 4110);
FORCEPROP 2 LAST CDS_LIB mstr_standard
J 2
(-1600 4100);
DISPLAY 0.787234 (-1600 4100);
PAINT MONO (-1600 4100);
DISPLAY INVISIBLE (-1600 4100);
FORCEPROP 1 LAST BODY_TYPE PLUMBING
J 2
(-1600 4050);
DISPLAY 1.234043 (-1600 4050);
PAINT GREEN (-1600 4050);
DISPLAY INVISIBLE (-1600 4050);
FORCEPROP 1 LAST HDL_TAP TRUE
J 2
(-1925 3975);
DISPLAY 1.234043 (-1925 3975);
PAINT GREEN (-1925 3975);
DISPLAY INVISIBLE (-1925 3975);
FORCEPROP 1 LAST PATH I127
J 2
(-1600 4100);
DISPLAY 0.936170 (-1600 4100);
PAINT GREEN (-1600 4100);
DISPLAY INVISIBLE (-1600 4100);
FORCEADD TAP..6
R 2
(-1600 4150);
FORCEPROP 3 LASTPIN (-1650 4150) SIG_NAME M_A_DQ<59>
J 0
(-1640 4160);
DISPLAY 0.659574 (-1640 4160);
PAINT MONO (-1640 4160);
DISPLAY INVISIBLE (-1640 4160);
FORCEPROP 1 LASTPIN (-1650 4150) BN 59
J 2
(-1600 4160);
DISPLAY 0.617021 (-1600 4160);
PAINT PINK (-1600 4160);
FORCEPROP 2 LAST CDS_LIB mstr_standard
J 2
(-1600 4150);
DISPLAY 0.787234 (-1600 4150);
PAINT MONO (-1600 4150);
DISPLAY INVISIBLE (-1600 4150);
FORCEPROP 1 LAST BODY_TYPE PLUMBING
J 2
(-1600 4100);
DISPLAY 1.234043 (-1600 4100);
PAINT GREEN (-1600 4100);
DISPLAY INVISIBLE (-1600 4100);
FORCEPROP 1 LAST HDL_TAP TRUE
J 2
(-1925 4025);
DISPLAY 1.234043 (-1925 4025);
PAINT GREEN (-1925 4025);
DISPLAY INVISIBLE (-1925 4025);
FORCEPROP 1 LAST PATH I128
J 2
(-1600 4150);
DISPLAY 0.936170 (-1600 4150);
PAINT GREEN (-1600 4150);
DISPLAY INVISIBLE (-1600 4150);
FORCEADD TAP..6
R 2
(-1600 4200);
FORCEPROP 3 LASTPIN (-1650 4200) SIG_NAME M_A_DQ<58>
J 0
(-1640 4210);
DISPLAY 0.659574 (-1640 4210);
PAINT MONO (-1640 4210);
DISPLAY INVISIBLE (-1640 4210);
FORCEPROP 1 LASTPIN (-1650 4200) BN 58
J 2
(-1600 4210);
DISPLAY 0.617021 (-1600 4210);
PAINT PINK (-1600 4210);
FORCEPROP 2 LAST CDS_LIB mstr_standard
J 2
(-1600 4200);
DISPLAY 0.787234 (-1600 4200);
PAINT MONO (-1600 4200);
DISPLAY INVISIBLE (-1600 4200);
FORCEPROP 1 LAST BODY_TYPE PLUMBING
J 2
(-1600 4150);
DISPLAY 1.234043 (-1600 4150);
PAINT GREEN (-1600 4150);
DISPLAY INVISIBLE (-1600 4150);
FORCEPROP 1 LAST HDL_TAP TRUE
J 2
(-1925 4075);
DISPLAY 1.234043 (-1925 4075);
PAINT GREEN (-1925 4075);
DISPLAY INVISIBLE (-1925 4075);
FORCEPROP 1 LAST PATH I129
J 2
(-1600 4200);
DISPLAY 0.936170 (-1600 4200);
PAINT GREEN (-1600 4200);
DISPLAY INVISIBLE (-1600 4200);
FORCEADD TAP..6
R 2
(-1600 4250);
FORCEPROP 3 LASTPIN (-1650 4250) SIG_NAME M_A_DQ<61>
J 0
(-1640 4260);
DISPLAY 0.659574 (-1640 4260);
PAINT MONO (-1640 4260);
DISPLAY INVISIBLE (-1640 4260);
FORCEPROP 1 LASTPIN (-1650 4250) BN 61
J 2
(-1600 4260);
DISPLAY 0.617021 (-1600 4260);
PAINT PINK (-1600 4260);
FORCEPROP 2 LAST CDS_LIB mstr_standard
J 2
(-1600 4250);
DISPLAY 0.787234 (-1600 4250);
PAINT MONO (-1600 4250);
DISPLAY INVISIBLE (-1600 4250);
FORCEPROP 1 LAST BODY_TYPE PLUMBING
J 2
(-1600 4200);
DISPLAY 1.234043 (-1600 4200);
PAINT GREEN (-1600 4200);
DISPLAY INVISIBLE (-1600 4200);
FORCEPROP 1 LAST HDL_TAP TRUE
J 2
(-1925 4125);
DISPLAY 1.234043 (-1925 4125);
PAINT GREEN (-1925 4125);
DISPLAY INVISIBLE (-1925 4125);
FORCEPROP 1 LAST PATH I130
J 2
(-1600 4250);
DISPLAY 0.936170 (-1600 4250);
PAINT GREEN (-1600 4250);
DISPLAY INVISIBLE (-1600 4250);
FORCEADD TAP..6
R 2
(-1600 4350);
FORCEPROP 3 LASTPIN (-1650 4350) SIG_NAME M_A_DQ<63>
J 0
(-1640 4360);
DISPLAY 0.659574 (-1640 4360);
PAINT MONO (-1640 4360);
DISPLAY INVISIBLE (-1640 4360);
FORCEPROP 1 LASTPIN (-1650 4350) BN 63
J 2
(-1600 4360);
DISPLAY 0.617021 (-1600 4360);
PAINT PINK (-1600 4360);
FORCEPROP 2 LAST CDS_LIB mstr_standard
J 2
(-1600 4350);
DISPLAY 0.787234 (-1600 4350);
PAINT MONO (-1600 4350);
DISPLAY INVISIBLE (-1600 4350);
FORCEPROP 1 LAST BODY_TYPE PLUMBING
J 2
(-1600 4300);
DISPLAY 1.234043 (-1600 4300);
PAINT GREEN (-1600 4300);
DISPLAY INVISIBLE (-1600 4300);
FORCEPROP 1 LAST HDL_TAP TRUE
J 2
(-1925 4225);
DISPLAY 1.234043 (-1925 4225);
PAINT GREEN (-1925 4225);
DISPLAY INVISIBLE (-1925 4225);
FORCEPROP 1 LAST PATH I131
J 2
(-1600 4350);
DISPLAY 0.936170 (-1600 4350);
PAINT GREEN (-1600 4350);
DISPLAY INVISIBLE (-1600 4350);
FORCEADD TAP..6
R 2
(-1600 4300);
FORCEPROP 3 LASTPIN (-1650 4300) SIG_NAME M_A_DQ<60>
J 0
(-1640 4310);
DISPLAY 0.659574 (-1640 4310);
PAINT MONO (-1640 4310);
DISPLAY INVISIBLE (-1640 4310);
FORCEPROP 1 LASTPIN (-1650 4300) BN 60
J 2
(-1600 4310);
DISPLAY 0.617021 (-1600 4310);
PAINT PINK (-1600 4310);
FORCEPROP 2 LAST CDS_LIB mstr_standard
J 2
(-1600 4300);
DISPLAY 0.787234 (-1600 4300);
PAINT MONO (-1600 4300);
DISPLAY INVISIBLE (-1600 4300);
FORCEPROP 1 LAST BODY_TYPE PLUMBING
J 2
(-1600 4250);
DISPLAY 1.234043 (-1600 4250);
PAINT GREEN (-1600 4250);
DISPLAY INVISIBLE (-1600 4250);
FORCEPROP 1 LAST HDL_TAP TRUE
J 2
(-1925 4175);
DISPLAY 1.234043 (-1925 4175);
PAINT GREEN (-1925 4175);
DISPLAY INVISIBLE (-1925 4175);
FORCEPROP 1 LAST PATH I132
J 2
(-1600 4300);
DISPLAY 0.936170 (-1600 4300);
PAINT GREEN (-1600 4300);
DISPLAY INVISIBLE (-1600 4300);
FORCEADD TAP..6
R 2
(-1600 4400);
FORCEPROP 3 LASTPIN (-1650 4400) SIG_NAME M_A_DQ<62>
J 0
(-1640 4410);
DISPLAY 0.659574 (-1640 4410);
PAINT MONO (-1640 4410);
DISPLAY INVISIBLE (-1640 4410);
FORCEPROP 1 LASTPIN (-1650 4400) BN 62
J 2
(-1600 4410);
DISPLAY 0.617021 (-1600 4410);
PAINT PINK (-1600 4410);
FORCEPROP 2 LAST CDS_LIB mstr_standard
J 2
(-1600 4400);
DISPLAY 0.787234 (-1600 4400);
PAINT MONO (-1600 4400);
DISPLAY INVISIBLE (-1600 4400);
FORCEPROP 1 LAST BODY_TYPE PLUMBING
J 2
(-1600 4350);
DISPLAY 1.234043 (-1600 4350);
PAINT GREEN (-1600 4350);
DISPLAY INVISIBLE (-1600 4350);
FORCEPROP 1 LAST HDL_TAP TRUE
J 2
(-1925 4275);
DISPLAY 1.234043 (-1925 4275);
PAINT GREEN (-1925 4275);
DISPLAY INVISIBLE (-1925 4275);
FORCEPROP 1 LAST PATH I133
J 2
(-1600 4400);
DISPLAY 0.936170 (-1600 4400);
PAINT GREEN (-1600 4400);
DISPLAY INVISIBLE (-1600 4400);
FORCEADD TAP..6
R 2
(-1600 3750);
FORCEPROP 3 LASTPIN (-1650 3750) SIG_NAME M_A_DQ<51>
J 0
(-1640 3760);
DISPLAY 0.659574 (-1640 3760);
PAINT MONO (-1640 3760);
DISPLAY INVISIBLE (-1640 3760);
FORCEPROP 1 LASTPIN (-1650 3750) BN 51
J 2
(-1600 3760);
DISPLAY 0.617021 (-1600 3760);
PAINT PINK (-1600 3760);
FORCEPROP 2 LAST CDS_LIB mstr_standard
J 2
(-1600 3750);
DISPLAY 0.787234 (-1600 3750);
PAINT MONO (-1600 3750);
DISPLAY INVISIBLE (-1600 3750);
FORCEPROP 1 LAST BODY_TYPE PLUMBING
J 2
(-1600 3700);
DISPLAY 1.234043 (-1600 3700);
PAINT GREEN (-1600 3700);
DISPLAY INVISIBLE (-1600 3700);
FORCEPROP 1 LAST HDL_TAP TRUE
J 2
(-1925 3625);
DISPLAY 1.234043 (-1925 3625);
PAINT GREEN (-1925 3625);
DISPLAY INVISIBLE (-1925 3625);
FORCEPROP 1 LAST PATH I134
J 2
(-1600 3750);
DISPLAY 0.936170 (-1600 3750);
PAINT GREEN (-1600 3750);
DISPLAY INVISIBLE (-1600 3750);
FORCEADD TAP..6
R 2
(-1600 3800);
FORCEPROP 3 LASTPIN (-1650 3800) SIG_NAME M_A_DQ<50>
J 0
(-1640 3810);
DISPLAY 0.659574 (-1640 3810);
PAINT MONO (-1640 3810);
DISPLAY INVISIBLE (-1640 3810);
FORCEPROP 1 LASTPIN (-1650 3800) BN 50
J 2
(-1600 3810);
DISPLAY 0.617021 (-1600 3810);
PAINT PINK (-1600 3810);
FORCEPROP 2 LAST CDS_LIB mstr_standard
J 2
(-1600 3800);
DISPLAY 0.787234 (-1600 3800);
PAINT MONO (-1600 3800);
DISPLAY INVISIBLE (-1600 3800);
FORCEPROP 1 LAST BODY_TYPE PLUMBING
J 2
(-1600 3750);
DISPLAY 1.234043 (-1600 3750);
PAINT GREEN (-1600 3750);
DISPLAY INVISIBLE (-1600 3750);
FORCEPROP 1 LAST HDL_TAP TRUE
J 2
(-1925 3675);
DISPLAY 1.234043 (-1925 3675);
PAINT GREEN (-1925 3675);
DISPLAY INVISIBLE (-1925 3675);
FORCEPROP 1 LAST PATH I135
J 2
(-1600 3800);
DISPLAY 0.936170 (-1600 3800);
PAINT GREEN (-1600 3800);
DISPLAY INVISIBLE (-1600 3800);
FORCEADD TAP..6
R 2
(-1600 3900);
FORCEPROP 3 LASTPIN (-1650 3900) SIG_NAME M_A_DQ<52>
J 0
(-1640 3910);
DISPLAY 0.659574 (-1640 3910);
PAINT MONO (-1640 3910);
DISPLAY INVISIBLE (-1640 3910);
FORCEPROP 1 LASTPIN (-1650 3900) BN 52
J 2
(-1600 3910);
DISPLAY 0.617021 (-1600 3910);
PAINT PINK (-1600 3910);
FORCEPROP 2 LAST CDS_LIB mstr_standard
J 2
(-1600 3900);
DISPLAY 0.787234 (-1600 3900);
PAINT MONO (-1600 3900);
DISPLAY INVISIBLE (-1600 3900);
FORCEPROP 1 LAST BODY_TYPE PLUMBING
J 2
(-1600 3850);
DISPLAY 1.234043 (-1600 3850);
PAINT GREEN (-1600 3850);
DISPLAY INVISIBLE (-1600 3850);
FORCEPROP 1 LAST HDL_TAP TRUE
J 2
(-1925 3775);
DISPLAY 1.234043 (-1925 3775);
PAINT GREEN (-1925 3775);
DISPLAY INVISIBLE (-1925 3775);
FORCEPROP 1 LAST PATH I136
J 2
(-1600 3900);
DISPLAY 0.936170 (-1600 3900);
PAINT GREEN (-1600 3900);
DISPLAY INVISIBLE (-1600 3900);
FORCEADD TAP..6
R 2
(-1600 3850);
FORCEPROP 3 LASTPIN (-1650 3850) SIG_NAME M_A_DQ<53>
J 0
(-1640 3860);
DISPLAY 0.659574 (-1640 3860);
PAINT MONO (-1640 3860);
DISPLAY INVISIBLE (-1640 3860);
FORCEPROP 1 LASTPIN (-1650 3850) BN 53
J 2
(-1600 3860);
DISPLAY 0.617021 (-1600 3860);
PAINT PINK (-1600 3860);
FORCEPROP 2 LAST CDS_LIB mstr_standard
J 2
(-1600 3850);
DISPLAY 0.787234 (-1600 3850);
PAINT MONO (-1600 3850);
DISPLAY INVISIBLE (-1600 3850);
FORCEPROP 1 LAST BODY_TYPE PLUMBING
J 2
(-1600 3800);
DISPLAY 1.234043 (-1600 3800);
PAINT GREEN (-1600 3800);
DISPLAY INVISIBLE (-1600 3800);
FORCEPROP 1 LAST HDL_TAP TRUE
J 2
(-1925 3725);
DISPLAY 1.234043 (-1925 3725);
PAINT GREEN (-1925 3725);
DISPLAY INVISIBLE (-1925 3725);
FORCEPROP 1 LAST PATH I137
J 2
(-1600 3850);
DISPLAY 0.936170 (-1600 3850);
PAINT GREEN (-1600 3850);
DISPLAY INVISIBLE (-1600 3850);
FORCEADD TAP..6
R 2
(-1600 3950);
FORCEPROP 3 LASTPIN (-1650 3950) SIG_NAME M_A_DQ<55>
J 0
(-1640 3960);
DISPLAY 0.659574 (-1640 3960);
PAINT MONO (-1640 3960);
DISPLAY INVISIBLE (-1640 3960);
FORCEPROP 1 LASTPIN (-1650 3950) BN 55
J 2
(-1600 3960);
DISPLAY 0.617021 (-1600 3960);
PAINT PINK (-1600 3960);
FORCEPROP 2 LAST CDS_LIB mstr_standard
J 2
(-1600 3950);
DISPLAY 0.787234 (-1600 3950);
PAINT MONO (-1600 3950);
DISPLAY INVISIBLE (-1600 3950);
FORCEPROP 1 LAST BODY_TYPE PLUMBING
J 2
(-1600 3900);
DISPLAY 1.234043 (-1600 3900);
PAINT GREEN (-1600 3900);
DISPLAY INVISIBLE (-1600 3900);
FORCEPROP 1 LAST HDL_TAP TRUE
J 2
(-1925 3825);
DISPLAY 1.234043 (-1925 3825);
PAINT GREEN (-1925 3825);
DISPLAY INVISIBLE (-1925 3825);
FORCEPROP 1 LAST PATH I138
J 2
(-1600 3950);
DISPLAY 0.936170 (-1600 3950);
PAINT GREEN (-1600 3950);
DISPLAY INVISIBLE (-1600 3950);
FORCEADD TAP..6
R 2
(-1600 4000);
FORCEPROP 3 LASTPIN (-1650 4000) SIG_NAME M_A_DQ<54>
J 0
(-1640 4010);
DISPLAY 0.659574 (-1640 4010);
PAINT MONO (-1640 4010);
DISPLAY INVISIBLE (-1640 4010);
FORCEPROP 1 LASTPIN (-1650 4000) BN 54
J 2
(-1600 4010);
DISPLAY 0.617021 (-1600 4010);
PAINT PINK (-1600 4010);
FORCEPROP 2 LAST CDS_LIB mstr_standard
J 2
(-1600 4000);
DISPLAY 0.787234 (-1600 4000);
PAINT MONO (-1600 4000);
DISPLAY INVISIBLE (-1600 4000);
FORCEPROP 1 LAST BODY_TYPE PLUMBING
J 2
(-1600 3950);
DISPLAY 1.234043 (-1600 3950);
PAINT GREEN (-1600 3950);
DISPLAY INVISIBLE (-1600 3950);
FORCEPROP 1 LAST HDL_TAP TRUE
J 2
(-1925 3875);
DISPLAY 1.234043 (-1925 3875);
PAINT GREEN (-1925 3875);
DISPLAY INVISIBLE (-1925 3875);
FORCEPROP 1 LAST PATH I139
J 2
(-1600 4000);
DISPLAY 0.936170 (-1600 4000);
PAINT GREEN (-1600 4000);
DISPLAY INVISIBLE (-1600 4000);
FORCEADD TAP..6
R 2
(-1600 4050);
FORCEPROP 3 LASTPIN (-1650 4050) SIG_NAME M_A_DQ<57>
J 0
(-1640 4060);
DISPLAY 0.659574 (-1640 4060);
PAINT MONO (-1640 4060);
DISPLAY INVISIBLE (-1640 4060);
FORCEPROP 1 LASTPIN (-1650 4050) BN 57
J 2
(-1600 4060);
DISPLAY 0.617021 (-1600 4060);
PAINT PINK (-1600 4060);
FORCEPROP 2 LAST CDS_LIB mstr_standard
J 2
(-1600 4050);
DISPLAY 0.787234 (-1600 4050);
PAINT MONO (-1600 4050);
DISPLAY INVISIBLE (-1600 4050);
FORCEPROP 1 LAST BODY_TYPE PLUMBING
J 2
(-1600 4000);
DISPLAY 1.234043 (-1600 4000);
PAINT GREEN (-1600 4000);
DISPLAY INVISIBLE (-1600 4000);
FORCEPROP 1 LAST HDL_TAP TRUE
J 2
(-1925 3925);
DISPLAY 1.234043 (-1925 3925);
PAINT GREEN (-1925 3925);
DISPLAY INVISIBLE (-1925 3925);
FORCEPROP 1 LAST PATH I140
J 2
(-1600 4050);
DISPLAY 0.936170 (-1600 4050);
PAINT GREEN (-1600 4050);
DISPLAY INVISIBLE (-1600 4050);
FORCEADD TAP..6
R 2
(-1600 3700);
FORCEPROP 3 LASTPIN (-1650 3700) SIG_NAME M_A_DQ<48>
J 0
(-1640 3710);
DISPLAY 0.659574 (-1640 3710);
PAINT MONO (-1640 3710);
DISPLAY INVISIBLE (-1640 3710);
FORCEPROP 1 LASTPIN (-1650 3700) BN 48
J 2
(-1600 3710);
DISPLAY 0.617021 (-1600 3710);
PAINT PINK (-1600 3710);
FORCEPROP 2 LAST CDS_LIB mstr_standard
J 2
(-1600 3700);
DISPLAY 0.787234 (-1600 3700);
PAINT MONO (-1600 3700);
DISPLAY INVISIBLE (-1600 3700);
FORCEPROP 1 LAST BODY_TYPE PLUMBING
J 2
(-1600 3650);
DISPLAY 1.234043 (-1600 3650);
PAINT GREEN (-1600 3650);
DISPLAY INVISIBLE (-1600 3650);
FORCEPROP 1 LAST HDL_TAP TRUE
J 2
(-1925 3575);
DISPLAY 1.234043 (-1925 3575);
PAINT GREEN (-1925 3575);
DISPLAY INVISIBLE (-1925 3575);
FORCEPROP 1 LAST PATH I141
J 2
(-1600 3700);
DISPLAY 0.936170 (-1600 3700);
PAINT GREEN (-1600 3700);
DISPLAY INVISIBLE (-1600 3700);
FORCEADD TAP..6
R 2
(-1600 2750);
FORCEPROP 3 LASTPIN (-1650 2750) SIG_NAME M_A_DQ<31>
J 0
(-1640 2760);
DISPLAY 0.659574 (-1640 2760);
PAINT MONO (-1640 2760);
DISPLAY INVISIBLE (-1640 2760);
FORCEPROP 1 LASTPIN (-1650 2750) BN 31
J 2
(-1600 2760);
DISPLAY 0.617021 (-1600 2760);
PAINT PINK (-1600 2760);
FORCEPROP 2 LAST CDS_LIB mstr_standard
J 2
(-1600 2750);
DISPLAY 0.787234 (-1600 2750);
PAINT MONO (-1600 2750);
DISPLAY INVISIBLE (-1600 2750);
FORCEPROP 1 LAST BODY_TYPE PLUMBING
J 2
(-1600 2700);
DISPLAY 1.234043 (-1600 2700);
PAINT GREEN (-1600 2700);
DISPLAY INVISIBLE (-1600 2700);
FORCEPROP 1 LAST HDL_TAP TRUE
J 2
(-1925 2625);
DISPLAY 1.234043 (-1925 2625);
PAINT GREEN (-1925 2625);
DISPLAY INVISIBLE (-1925 2625);
FORCEPROP 1 LAST PATH I142
J 2
(-1600 2750);
DISPLAY 0.936170 (-1600 2750);
PAINT GREEN (-1600 2750);
DISPLAY INVISIBLE (-1600 2750);
FORCEADD TAP..6
R 2
(-1600 2700);
FORCEPROP 3 LASTPIN (-1650 2700) SIG_NAME M_A_DQ<28>
J 0
(-1640 2710);
DISPLAY 0.659574 (-1640 2710);
PAINT MONO (-1640 2710);
DISPLAY INVISIBLE (-1640 2710);
FORCEPROP 1 LASTPIN (-1650 2700) BN 28
J 2
(-1600 2710);
DISPLAY 0.617021 (-1600 2710);
PAINT PINK (-1600 2710);
FORCEPROP 2 LAST CDS_LIB mstr_standard
J 2
(-1600 2700);
DISPLAY 0.787234 (-1600 2700);
PAINT MONO (-1600 2700);
DISPLAY INVISIBLE (-1600 2700);
FORCEPROP 1 LAST BODY_TYPE PLUMBING
J 2
(-1600 2650);
DISPLAY 1.234043 (-1600 2650);
PAINT GREEN (-1600 2650);
DISPLAY INVISIBLE (-1600 2650);
FORCEPROP 1 LAST HDL_TAP TRUE
J 2
(-1925 2575);
DISPLAY 1.234043 (-1925 2575);
PAINT GREEN (-1925 2575);
DISPLAY INVISIBLE (-1925 2575);
FORCEPROP 1 LAST PATH I143
J 2
(-1600 2700);
DISPLAY 0.936170 (-1600 2700);
PAINT GREEN (-1600 2700);
DISPLAY INVISIBLE (-1600 2700);
FORCEADD TAP..6
R 2
(-1600 2800);
FORCEPROP 3 LASTPIN (-1650 2800) SIG_NAME M_A_DQ<30>
J 0
(-1640 2810);
DISPLAY 0.659574 (-1640 2810);
PAINT MONO (-1640 2810);
DISPLAY INVISIBLE (-1640 2810);
FORCEPROP 1 LASTPIN (-1650 2800) BN 30
J 2
(-1600 2810);
DISPLAY 0.617021 (-1600 2810);
PAINT PINK (-1600 2810);
FORCEPROP 2 LAST CDS_LIB mstr_standard
J 2
(-1600 2800);
DISPLAY 0.787234 (-1600 2800);
PAINT MONO (-1600 2800);
DISPLAY INVISIBLE (-1600 2800);
FORCEPROP 1 LAST BODY_TYPE PLUMBING
J 2
(-1600 2750);
DISPLAY 1.234043 (-1600 2750);
PAINT GREEN (-1600 2750);
DISPLAY INVISIBLE (-1600 2750);
FORCEPROP 1 LAST HDL_TAP TRUE
J 2
(-1925 2675);
DISPLAY 1.234043 (-1925 2675);
PAINT GREEN (-1925 2675);
DISPLAY INVISIBLE (-1925 2675);
FORCEPROP 1 LAST PATH I144
J 2
(-1600 2800);
DISPLAY 0.936170 (-1600 2800);
PAINT GREEN (-1600 2800);
DISPLAY INVISIBLE (-1600 2800);
FORCEADD TAP..6
R 2
(-1600 2850);
FORCEPROP 3 LASTPIN (-1650 2850) SIG_NAME M_A_DQ<33>
J 0
(-1640 2860);
DISPLAY 0.659574 (-1640 2860);
PAINT MONO (-1640 2860);
DISPLAY INVISIBLE (-1640 2860);
FORCEPROP 1 LASTPIN (-1650 2850) BN 33
J 2
(-1600 2860);
DISPLAY 0.617021 (-1600 2860);
PAINT PINK (-1600 2860);
FORCEPROP 2 LAST CDS_LIB mstr_standard
J 2
(-1600 2850);
DISPLAY 0.787234 (-1600 2850);
PAINT MONO (-1600 2850);
DISPLAY INVISIBLE (-1600 2850);
FORCEPROP 1 LAST BODY_TYPE PLUMBING
J 2
(-1600 2800);
DISPLAY 1.234043 (-1600 2800);
PAINT GREEN (-1600 2800);
DISPLAY INVISIBLE (-1600 2800);
FORCEPROP 1 LAST HDL_TAP TRUE
J 2
(-1925 2725);
DISPLAY 1.234043 (-1925 2725);
PAINT GREEN (-1925 2725);
DISPLAY INVISIBLE (-1925 2725);
FORCEPROP 1 LAST PATH I145
J 2
(-1600 2850);
DISPLAY 0.936170 (-1600 2850);
PAINT GREEN (-1600 2850);
DISPLAY INVISIBLE (-1600 2850);
FORCEADD TAP..6
R 2
(-1600 2950);
FORCEPROP 3 LASTPIN (-1650 2950) SIG_NAME M_A_DQ<35>
J 0
(-1640 2960);
DISPLAY 0.659574 (-1640 2960);
PAINT MONO (-1640 2960);
DISPLAY INVISIBLE (-1640 2960);
FORCEPROP 1 LASTPIN (-1650 2950) BN 35
J 2
(-1600 2960);
DISPLAY 0.617021 (-1600 2960);
PAINT PINK (-1600 2960);
FORCEPROP 2 LAST CDS_LIB mstr_standard
J 2
(-1600 2950);
DISPLAY 0.787234 (-1600 2950);
PAINT MONO (-1600 2950);
DISPLAY INVISIBLE (-1600 2950);
FORCEPROP 1 LAST BODY_TYPE PLUMBING
J 2
(-1600 2900);
DISPLAY 1.234043 (-1600 2900);
PAINT GREEN (-1600 2900);
DISPLAY INVISIBLE (-1600 2900);
FORCEPROP 1 LAST HDL_TAP TRUE
J 2
(-1925 2825);
DISPLAY 1.234043 (-1925 2825);
PAINT GREEN (-1925 2825);
DISPLAY INVISIBLE (-1925 2825);
FORCEPROP 1 LAST PATH I146
J 2
(-1600 2950);
DISPLAY 0.936170 (-1600 2950);
PAINT GREEN (-1600 2950);
DISPLAY INVISIBLE (-1600 2950);
FORCEADD TAP..6
R 2
(-1600 2900);
FORCEPROP 3 LASTPIN (-1650 2900) SIG_NAME M_A_DQ<32>
J 0
(-1640 2910);
DISPLAY 0.659574 (-1640 2910);
PAINT MONO (-1640 2910);
DISPLAY INVISIBLE (-1640 2910);
FORCEPROP 1 LASTPIN (-1650 2900) BN 32
J 2
(-1600 2910);
DISPLAY 0.617021 (-1600 2910);
PAINT PINK (-1600 2910);
FORCEPROP 2 LAST CDS_LIB mstr_standard
J 2
(-1600 2900);
DISPLAY 0.787234 (-1600 2900);
PAINT MONO (-1600 2900);
DISPLAY INVISIBLE (-1600 2900);
FORCEPROP 1 LAST BODY_TYPE PLUMBING
J 2
(-1600 2850);
DISPLAY 1.234043 (-1600 2850);
PAINT GREEN (-1600 2850);
DISPLAY INVISIBLE (-1600 2850);
FORCEPROP 1 LAST HDL_TAP TRUE
J 2
(-1925 2775);
DISPLAY 1.234043 (-1925 2775);
PAINT GREEN (-1925 2775);
DISPLAY INVISIBLE (-1925 2775);
FORCEPROP 1 LAST PATH I147
J 2
(-1600 2900);
DISPLAY 0.936170 (-1600 2900);
PAINT GREEN (-1600 2900);
DISPLAY INVISIBLE (-1600 2900);
FORCEADD TAP..6
R 2
(-1600 3000);
FORCEPROP 3 LASTPIN (-1650 3000) SIG_NAME M_A_DQ<34>
J 0
(-1640 3010);
DISPLAY 0.659574 (-1640 3010);
PAINT MONO (-1640 3010);
DISPLAY INVISIBLE (-1640 3010);
FORCEPROP 1 LASTPIN (-1650 3000) BN 34
J 2
(-1600 3010);
DISPLAY 0.617021 (-1600 3010);
PAINT PINK (-1600 3010);
FORCEPROP 2 LAST CDS_LIB mstr_standard
J 2
(-1600 3000);
DISPLAY 0.787234 (-1600 3000);
PAINT MONO (-1600 3000);
DISPLAY INVISIBLE (-1600 3000);
FORCEPROP 1 LAST BODY_TYPE PLUMBING
J 2
(-1600 2950);
DISPLAY 1.234043 (-1600 2950);
PAINT GREEN (-1600 2950);
DISPLAY INVISIBLE (-1600 2950);
FORCEPROP 1 LAST HDL_TAP TRUE
J 2
(-1925 2875);
DISPLAY 1.234043 (-1925 2875);
PAINT GREEN (-1925 2875);
DISPLAY INVISIBLE (-1925 2875);
FORCEPROP 1 LAST PATH I148
J 2
(-1600 3000);
DISPLAY 0.936170 (-1600 3000);
PAINT GREEN (-1600 3000);
DISPLAY INVISIBLE (-1600 3000);
FORCEADD TAP..6
R 2
(-1600 3050);
FORCEPROP 3 LASTPIN (-1650 3050) SIG_NAME M_A_DQ<37>
J 0
(-1640 3060);
DISPLAY 0.659574 (-1640 3060);
PAINT MONO (-1640 3060);
DISPLAY INVISIBLE (-1640 3060);
FORCEPROP 1 LASTPIN (-1650 3050) BN 37
J 2
(-1600 3060);
DISPLAY 0.617021 (-1600 3060);
PAINT PINK (-1600 3060);
FORCEPROP 2 LAST CDS_LIB mstr_standard
J 2
(-1600 3050);
DISPLAY 0.787234 (-1600 3050);
PAINT MONO (-1600 3050);
DISPLAY INVISIBLE (-1600 3050);
FORCEPROP 1 LAST BODY_TYPE PLUMBING
J 2
(-1600 3000);
DISPLAY 1.234043 (-1600 3000);
PAINT GREEN (-1600 3000);
DISPLAY INVISIBLE (-1600 3000);
FORCEPROP 1 LAST HDL_TAP TRUE
J 2
(-1925 2925);
DISPLAY 1.234043 (-1925 2925);
PAINT GREEN (-1925 2925);
DISPLAY INVISIBLE (-1925 2925);
FORCEPROP 1 LAST PATH I149
J 2
(-1600 3050);
DISPLAY 0.936170 (-1600 3050);
PAINT GREEN (-1600 3050);
DISPLAY INVISIBLE (-1600 3050);
FORCEADD TAP..6
R 2
(-1600 3100);
FORCEPROP 3 LASTPIN (-1650 3100) SIG_NAME M_A_DQ<36>
J 0
(-1640 3110);
DISPLAY 0.659574 (-1640 3110);
PAINT MONO (-1640 3110);
DISPLAY INVISIBLE (-1640 3110);
FORCEPROP 1 LASTPIN (-1650 3100) BN 36
J 2
(-1600 3110);
DISPLAY 0.617021 (-1600 3110);
PAINT PINK (-1600 3110);
FORCEPROP 2 LAST CDS_LIB mstr_standard
J 2
(-1600 3100);
DISPLAY 0.787234 (-1600 3100);
PAINT MONO (-1600 3100);
DISPLAY INVISIBLE (-1600 3100);
FORCEPROP 1 LAST BODY_TYPE PLUMBING
J 2
(-1600 3050);
DISPLAY 1.234043 (-1600 3050);
PAINT GREEN (-1600 3050);
DISPLAY INVISIBLE (-1600 3050);
FORCEPROP 1 LAST HDL_TAP TRUE
J 2
(-1925 2975);
DISPLAY 1.234043 (-1925 2975);
PAINT GREEN (-1925 2975);
DISPLAY INVISIBLE (-1925 2975);
FORCEPROP 1 LAST PATH I150
J 2
(-1600 3100);
DISPLAY 0.936170 (-1600 3100);
PAINT GREEN (-1600 3100);
DISPLAY INVISIBLE (-1600 3100);
FORCEADD TAP..6
R 2
(-1600 3200);
FORCEPROP 3 LASTPIN (-1650 3200) SIG_NAME M_A_DQ<38>
J 0
(-1640 3210);
DISPLAY 0.659574 (-1640 3210);
PAINT MONO (-1640 3210);
DISPLAY INVISIBLE (-1640 3210);
FORCEPROP 1 LASTPIN (-1650 3200) BN 38
J 2
(-1600 3210);
DISPLAY 0.617021 (-1600 3210);
PAINT PINK (-1600 3210);
FORCEPROP 2 LAST CDS_LIB mstr_standard
J 2
(-1600 3200);
DISPLAY 0.787234 (-1600 3200);
PAINT MONO (-1600 3200);
DISPLAY INVISIBLE (-1600 3200);
FORCEPROP 1 LAST BODY_TYPE PLUMBING
J 2
(-1600 3150);
DISPLAY 1.234043 (-1600 3150);
PAINT GREEN (-1600 3150);
DISPLAY INVISIBLE (-1600 3150);
FORCEPROP 1 LAST HDL_TAP TRUE
J 2
(-1925 3075);
DISPLAY 1.234043 (-1925 3075);
PAINT GREEN (-1925 3075);
DISPLAY INVISIBLE (-1925 3075);
FORCEPROP 1 LAST PATH I151
J 2
(-1600 3200);
DISPLAY 0.936170 (-1600 3200);
PAINT GREEN (-1600 3200);
DISPLAY INVISIBLE (-1600 3200);
FORCEADD TAP..6
R 2
(-1600 3150);
FORCEPROP 3 LASTPIN (-1650 3150) SIG_NAME M_A_DQ<39>
J 0
(-1640 3160);
DISPLAY 0.659574 (-1640 3160);
PAINT MONO (-1640 3160);
DISPLAY INVISIBLE (-1640 3160);
FORCEPROP 1 LASTPIN (-1650 3150) BN 39
J 2
(-1600 3160);
DISPLAY 0.617021 (-1600 3160);
PAINT PINK (-1600 3160);
FORCEPROP 2 LAST CDS_LIB mstr_standard
J 2
(-1600 3150);
DISPLAY 0.787234 (-1600 3150);
PAINT MONO (-1600 3150);
DISPLAY INVISIBLE (-1600 3150);
FORCEPROP 1 LAST BODY_TYPE PLUMBING
J 2
(-1600 3100);
DISPLAY 1.234043 (-1600 3100);
PAINT GREEN (-1600 3100);
DISPLAY INVISIBLE (-1600 3100);
FORCEPROP 1 LAST HDL_TAP TRUE
J 2
(-1925 3025);
DISPLAY 1.234043 (-1925 3025);
PAINT GREEN (-1925 3025);
DISPLAY INVISIBLE (-1925 3025);
FORCEPROP 1 LAST PATH I152
J 2
(-1600 3150);
DISPLAY 0.936170 (-1600 3150);
PAINT GREEN (-1600 3150);
DISPLAY INVISIBLE (-1600 3150);
FORCEADD TAP..6
R 2
(-1600 3250);
FORCEPROP 3 LASTPIN (-1650 3250) SIG_NAME M_A_DQ<41>
J 0
(-1640 3260);
DISPLAY 0.659574 (-1640 3260);
PAINT MONO (-1640 3260);
DISPLAY INVISIBLE (-1640 3260);
FORCEPROP 1 LASTPIN (-1650 3250) BN 41
J 2
(-1600 3260);
DISPLAY 0.617021 (-1600 3260);
PAINT PINK (-1600 3260);
FORCEPROP 2 LAST CDS_LIB mstr_standard
J 2
(-1600 3250);
DISPLAY 0.787234 (-1600 3250);
PAINT MONO (-1600 3250);
DISPLAY INVISIBLE (-1600 3250);
FORCEPROP 1 LAST BODY_TYPE PLUMBING
J 2
(-1600 3200);
DISPLAY 1.234043 (-1600 3200);
PAINT GREEN (-1600 3200);
DISPLAY INVISIBLE (-1600 3200);
FORCEPROP 1 LAST HDL_TAP TRUE
J 2
(-1925 3125);
DISPLAY 1.234043 (-1925 3125);
PAINT GREEN (-1925 3125);
DISPLAY INVISIBLE (-1925 3125);
FORCEPROP 1 LAST PATH I153
J 2
(-1600 3250);
DISPLAY 0.936170 (-1600 3250);
PAINT GREEN (-1600 3250);
DISPLAY INVISIBLE (-1600 3250);
FORCEADD TAP..6
R 2
(-1600 3300);
FORCEPROP 3 LASTPIN (-1650 3300) SIG_NAME M_A_DQ<40>
J 0
(-1640 3310);
DISPLAY 0.659574 (-1640 3310);
PAINT MONO (-1640 3310);
DISPLAY INVISIBLE (-1640 3310);
FORCEPROP 1 LASTPIN (-1650 3300) BN 40
J 2
(-1600 3310);
DISPLAY 0.617021 (-1600 3310);
PAINT PINK (-1600 3310);
FORCEPROP 2 LAST CDS_LIB mstr_standard
J 2
(-1600 3300);
DISPLAY 0.787234 (-1600 3300);
PAINT MONO (-1600 3300);
DISPLAY INVISIBLE (-1600 3300);
FORCEPROP 1 LAST BODY_TYPE PLUMBING
J 2
(-1600 3250);
DISPLAY 1.234043 (-1600 3250);
PAINT GREEN (-1600 3250);
DISPLAY INVISIBLE (-1600 3250);
FORCEPROP 1 LAST HDL_TAP TRUE
J 2
(-1925 3175);
DISPLAY 1.234043 (-1925 3175);
PAINT GREEN (-1925 3175);
DISPLAY INVISIBLE (-1925 3175);
FORCEPROP 1 LAST PATH I154
J 2
(-1600 3300);
DISPLAY 0.936170 (-1600 3300);
PAINT GREEN (-1600 3300);
DISPLAY INVISIBLE (-1600 3300);
FORCEADD TAP..6
R 2
(-1600 3350);
FORCEPROP 3 LASTPIN (-1650 3350) SIG_NAME M_A_DQ<43>
J 0
(-1640 3360);
DISPLAY 0.659574 (-1640 3360);
PAINT MONO (-1640 3360);
DISPLAY INVISIBLE (-1640 3360);
FORCEPROP 1 LASTPIN (-1650 3350) BN 43
J 2
(-1600 3360);
DISPLAY 0.617021 (-1600 3360);
PAINT PINK (-1600 3360);
FORCEPROP 2 LAST CDS_LIB mstr_standard
J 2
(-1600 3350);
DISPLAY 0.787234 (-1600 3350);
PAINT MONO (-1600 3350);
DISPLAY INVISIBLE (-1600 3350);
FORCEPROP 1 LAST BODY_TYPE PLUMBING
J 2
(-1600 3300);
DISPLAY 1.234043 (-1600 3300);
PAINT GREEN (-1600 3300);
DISPLAY INVISIBLE (-1600 3300);
FORCEPROP 1 LAST HDL_TAP TRUE
J 2
(-1925 3225);
DISPLAY 1.234043 (-1925 3225);
PAINT GREEN (-1925 3225);
DISPLAY INVISIBLE (-1925 3225);
FORCEPROP 1 LAST PATH I155
J 2
(-1600 3350);
DISPLAY 0.936170 (-1600 3350);
PAINT GREEN (-1600 3350);
DISPLAY INVISIBLE (-1600 3350);
FORCEADD TAP..6
R 2
(-1600 3450);
FORCEPROP 3 LASTPIN (-1650 3450) SIG_NAME M_A_DQ<45>
J 0
(-1640 3460);
DISPLAY 0.659574 (-1640 3460);
PAINT MONO (-1640 3460);
DISPLAY INVISIBLE (-1640 3460);
FORCEPROP 1 LASTPIN (-1650 3450) BN 45
J 2
(-1600 3460);
DISPLAY 0.617021 (-1600 3460);
PAINT PINK (-1600 3460);
FORCEPROP 2 LAST CDS_LIB mstr_standard
J 2
(-1600 3450);
DISPLAY 0.787234 (-1600 3450);
PAINT MONO (-1600 3450);
DISPLAY INVISIBLE (-1600 3450);
FORCEPROP 1 LAST BODY_TYPE PLUMBING
J 2
(-1600 3400);
DISPLAY 1.234043 (-1600 3400);
PAINT GREEN (-1600 3400);
DISPLAY INVISIBLE (-1600 3400);
FORCEPROP 1 LAST HDL_TAP TRUE
J 2
(-1925 3325);
DISPLAY 1.234043 (-1925 3325);
PAINT GREEN (-1925 3325);
DISPLAY INVISIBLE (-1925 3325);
FORCEPROP 1 LAST PATH I156
J 2
(-1600 3450);
DISPLAY 0.936170 (-1600 3450);
PAINT GREEN (-1600 3450);
DISPLAY INVISIBLE (-1600 3450);
FORCEADD TAP..6
R 2
(-1600 3400);
FORCEPROP 3 LASTPIN (-1650 3400) SIG_NAME M_A_DQ<42>
J 0
(-1640 3410);
DISPLAY 0.659574 (-1640 3410);
PAINT MONO (-1640 3410);
DISPLAY INVISIBLE (-1640 3410);
FORCEPROP 1 LASTPIN (-1650 3400) BN 42
J 2
(-1600 3410);
DISPLAY 0.617021 (-1600 3410);
PAINT PINK (-1600 3410);
FORCEPROP 2 LAST CDS_LIB mstr_standard
J 2
(-1600 3400);
DISPLAY 0.787234 (-1600 3400);
PAINT MONO (-1600 3400);
DISPLAY INVISIBLE (-1600 3400);
FORCEPROP 1 LAST BODY_TYPE PLUMBING
J 2
(-1600 3350);
DISPLAY 1.234043 (-1600 3350);
PAINT GREEN (-1600 3350);
DISPLAY INVISIBLE (-1600 3350);
FORCEPROP 1 LAST HDL_TAP TRUE
J 2
(-1925 3275);
DISPLAY 1.234043 (-1925 3275);
PAINT GREEN (-1925 3275);
DISPLAY INVISIBLE (-1925 3275);
FORCEPROP 1 LAST PATH I157
J 2
(-1600 3400);
DISPLAY 0.936170 (-1600 3400);
PAINT GREEN (-1600 3400);
DISPLAY INVISIBLE (-1600 3400);
FORCEADD TAP..6
R 2
(-1600 3500);
FORCEPROP 3 LASTPIN (-1650 3500) SIG_NAME M_A_DQ<44>
J 0
(-1640 3510);
DISPLAY 0.659574 (-1640 3510);
PAINT MONO (-1640 3510);
DISPLAY INVISIBLE (-1640 3510);
FORCEPROP 1 LASTPIN (-1650 3500) BN 44
J 2
(-1600 3510);
DISPLAY 0.617021 (-1600 3510);
PAINT PINK (-1600 3510);
FORCEPROP 2 LAST CDS_LIB mstr_standard
J 2
(-1600 3500);
DISPLAY 0.787234 (-1600 3500);
PAINT MONO (-1600 3500);
DISPLAY INVISIBLE (-1600 3500);
FORCEPROP 1 LAST BODY_TYPE PLUMBING
J 2
(-1600 3450);
DISPLAY 1.234043 (-1600 3450);
PAINT GREEN (-1600 3450);
DISPLAY INVISIBLE (-1600 3450);
FORCEPROP 1 LAST HDL_TAP TRUE
J 2
(-1925 3375);
DISPLAY 1.234043 (-1925 3375);
PAINT GREEN (-1925 3375);
DISPLAY INVISIBLE (-1925 3375);
FORCEPROP 1 LAST PATH I158
J 2
(-1600 3500);
DISPLAY 0.936170 (-1600 3500);
PAINT GREEN (-1600 3500);
DISPLAY INVISIBLE (-1600 3500);
FORCEADD TAP..6
R 2
(-1600 3550);
FORCEPROP 3 LASTPIN (-1650 3550) SIG_NAME M_A_DQ<47>
J 0
(-1640 3560);
DISPLAY 0.659574 (-1640 3560);
PAINT MONO (-1640 3560);
DISPLAY INVISIBLE (-1640 3560);
FORCEPROP 1 LASTPIN (-1650 3550) BN 47
J 2
(-1600 3560);
DISPLAY 0.617021 (-1600 3560);
PAINT PINK (-1600 3560);
FORCEPROP 2 LAST CDS_LIB mstr_standard
J 2
(-1600 3550);
DISPLAY 0.787234 (-1600 3550);
PAINT MONO (-1600 3550);
DISPLAY INVISIBLE (-1600 3550);
FORCEPROP 1 LAST BODY_TYPE PLUMBING
J 2
(-1600 3500);
DISPLAY 1.234043 (-1600 3500);
PAINT GREEN (-1600 3500);
DISPLAY INVISIBLE (-1600 3500);
FORCEPROP 1 LAST HDL_TAP TRUE
J 2
(-1925 3425);
DISPLAY 1.234043 (-1925 3425);
PAINT GREEN (-1925 3425);
DISPLAY INVISIBLE (-1925 3425);
FORCEPROP 1 LAST PATH I159
J 2
(-1600 3550);
DISPLAY 0.936170 (-1600 3550);
PAINT GREEN (-1600 3550);
DISPLAY INVISIBLE (-1600 3550);
FORCEADD TAP..6
R 2
(-1600 3650);
FORCEPROP 3 LASTPIN (-1650 3650) SIG_NAME M_A_DQ<49>
J 0
(-1640 3660);
DISPLAY 0.659574 (-1640 3660);
PAINT MONO (-1640 3660);
DISPLAY INVISIBLE (-1640 3660);
FORCEPROP 1 LASTPIN (-1650 3650) BN 49
J 2
(-1600 3660);
DISPLAY 0.617021 (-1600 3660);
PAINT PINK (-1600 3660);
FORCEPROP 2 LAST CDS_LIB mstr_standard
J 2
(-1600 3650);
DISPLAY 0.787234 (-1600 3650);
PAINT MONO (-1600 3650);
DISPLAY INVISIBLE (-1600 3650);
FORCEPROP 1 LAST BODY_TYPE PLUMBING
J 2
(-1600 3600);
DISPLAY 1.234043 (-1600 3600);
PAINT GREEN (-1600 3600);
DISPLAY INVISIBLE (-1600 3600);
FORCEPROP 1 LAST HDL_TAP TRUE
J 2
(-1925 3525);
DISPLAY 1.234043 (-1925 3525);
PAINT GREEN (-1925 3525);
DISPLAY INVISIBLE (-1925 3525);
FORCEPROP 1 LAST PATH I160
J 2
(-1600 3650);
DISPLAY 0.936170 (-1600 3650);
PAINT GREEN (-1600 3650);
DISPLAY INVISIBLE (-1600 3650);
FORCEADD TAP..6
R 2
(-1600 3600);
FORCEPROP 3 LASTPIN (-1650 3600) SIG_NAME M_A_DQ<46>
J 0
(-1640 3610);
DISPLAY 0.659574 (-1640 3610);
PAINT MONO (-1640 3610);
DISPLAY INVISIBLE (-1640 3610);
FORCEPROP 1 LASTPIN (-1650 3600) BN 46
J 2
(-1600 3610);
DISPLAY 0.617021 (-1600 3610);
PAINT PINK (-1600 3610);
FORCEPROP 2 LAST CDS_LIB mstr_standard
J 2
(-1600 3600);
DISPLAY 0.787234 (-1600 3600);
PAINT MONO (-1600 3600);
DISPLAY INVISIBLE (-1600 3600);
FORCEPROP 1 LAST BODY_TYPE PLUMBING
J 2
(-1600 3550);
DISPLAY 1.234043 (-1600 3550);
PAINT GREEN (-1600 3550);
DISPLAY INVISIBLE (-1600 3550);
FORCEPROP 1 LAST HDL_TAP TRUE
J 2
(-1925 3475);
DISPLAY 1.234043 (-1925 3475);
PAINT GREEN (-1925 3475);
DISPLAY INVISIBLE (-1925 3475);
FORCEPROP 1 LAST PATH I161
J 2
(-1600 3600);
DISPLAY 0.936170 (-1600 3600);
PAINT GREEN (-1600 3600);
DISPLAY INVISIBLE (-1600 3600);
FORCEADD TAP..6
R 2
(-1600 2050);
FORCEPROP 3 LASTPIN (-1650 2050) SIG_NAME M_A_DQ<17>
J 0
(-1640 2060);
DISPLAY 0.659574 (-1640 2060);
PAINT MONO (-1640 2060);
DISPLAY INVISIBLE (-1640 2060);
FORCEPROP 1 LASTPIN (-1650 2050) BN 17
J 2
(-1600 2060);
DISPLAY 0.617021 (-1600 2060);
PAINT PINK (-1600 2060);
FORCEPROP 2 LAST CDS_LIB mstr_standard
J 2
(-1600 2050);
DISPLAY 0.787234 (-1600 2050);
PAINT MONO (-1600 2050);
DISPLAY INVISIBLE (-1600 2050);
FORCEPROP 1 LAST BODY_TYPE PLUMBING
J 2
(-1600 2000);
DISPLAY 1.234043 (-1600 2000);
PAINT GREEN (-1600 2000);
DISPLAY INVISIBLE (-1600 2000);
FORCEPROP 1 LAST HDL_TAP TRUE
J 2
(-1925 1925);
DISPLAY 1.234043 (-1925 1925);
PAINT GREEN (-1925 1925);
DISPLAY INVISIBLE (-1925 1925);
FORCEPROP 1 LAST PATH I162
J 2
(-1600 2050);
DISPLAY 0.936170 (-1600 2050);
PAINT GREEN (-1600 2050);
DISPLAY INVISIBLE (-1600 2050);
FORCEADD TAP..6
R 2
(-1600 2000);
FORCEPROP 3 LASTPIN (-1650 2000) SIG_NAME M_A_DQ<14>
J 0
(-1640 2010);
DISPLAY 0.659574 (-1640 2010);
PAINT MONO (-1640 2010);
DISPLAY INVISIBLE (-1640 2010);
FORCEPROP 1 LASTPIN (-1650 2000) BN 14
J 2
(-1600 2010);
DISPLAY 0.617021 (-1600 2010);
PAINT PINK (-1600 2010);
FORCEPROP 2 LAST CDS_LIB mstr_standard
J 2
(-1600 2000);
DISPLAY 0.787234 (-1600 2000);
PAINT MONO (-1600 2000);
DISPLAY INVISIBLE (-1600 2000);
FORCEPROP 1 LAST BODY_TYPE PLUMBING
J 2
(-1600 1950);
DISPLAY 1.234043 (-1600 1950);
PAINT GREEN (-1600 1950);
DISPLAY INVISIBLE (-1600 1950);
FORCEPROP 1 LAST HDL_TAP TRUE
J 2
(-1925 1875);
DISPLAY 1.234043 (-1925 1875);
PAINT GREEN (-1925 1875);
DISPLAY INVISIBLE (-1925 1875);
FORCEPROP 1 LAST PATH I163
J 2
(-1600 2000);
DISPLAY 0.936170 (-1600 2000);
PAINT GREEN (-1600 2000);
DISPLAY INVISIBLE (-1600 2000);
FORCEADD TAP..6
R 2
(-1600 2100);
FORCEPROP 3 LASTPIN (-1650 2100) SIG_NAME M_A_DQ<16>
J 0
(-1640 2110);
DISPLAY 0.659574 (-1640 2110);
PAINT MONO (-1640 2110);
DISPLAY INVISIBLE (-1640 2110);
FORCEPROP 1 LASTPIN (-1650 2100) BN 16
J 2
(-1600 2110);
DISPLAY 0.617021 (-1600 2110);
PAINT PINK (-1600 2110);
FORCEPROP 2 LAST CDS_LIB mstr_standard
J 2
(-1600 2100);
DISPLAY 0.787234 (-1600 2100);
PAINT MONO (-1600 2100);
DISPLAY INVISIBLE (-1600 2100);
FORCEPROP 1 LAST BODY_TYPE PLUMBING
J 2
(-1600 2050);
DISPLAY 1.234043 (-1600 2050);
PAINT GREEN (-1600 2050);
DISPLAY INVISIBLE (-1600 2050);
FORCEPROP 1 LAST HDL_TAP TRUE
J 2
(-1925 1975);
DISPLAY 1.234043 (-1925 1975);
PAINT GREEN (-1925 1975);
DISPLAY INVISIBLE (-1925 1975);
FORCEPROP 1 LAST PATH I164
J 2
(-1600 2100);
DISPLAY 0.936170 (-1600 2100);
PAINT GREEN (-1600 2100);
DISPLAY INVISIBLE (-1600 2100);
FORCEADD TAP..6
R 2
(-1600 2150);
FORCEPROP 3 LASTPIN (-1650 2150) SIG_NAME M_A_DQ<19>
J 0
(-1640 2160);
DISPLAY 0.659574 (-1640 2160);
PAINT MONO (-1640 2160);
DISPLAY INVISIBLE (-1640 2160);
FORCEPROP 1 LASTPIN (-1650 2150) BN 19
J 2
(-1600 2160);
DISPLAY 0.617021 (-1600 2160);
PAINT PINK (-1600 2160);
FORCEPROP 2 LAST CDS_LIB mstr_standard
J 2
(-1600 2150);
DISPLAY 0.787234 (-1600 2150);
PAINT MONO (-1600 2150);
DISPLAY INVISIBLE (-1600 2150);
FORCEPROP 1 LAST BODY_TYPE PLUMBING
J 2
(-1600 2100);
DISPLAY 1.234043 (-1600 2100);
PAINT GREEN (-1600 2100);
DISPLAY INVISIBLE (-1600 2100);
FORCEPROP 1 LAST HDL_TAP TRUE
J 2
(-1925 2025);
DISPLAY 1.234043 (-1925 2025);
PAINT GREEN (-1925 2025);
DISPLAY INVISIBLE (-1925 2025);
FORCEPROP 1 LAST PATH I165
J 2
(-1600 2150);
DISPLAY 0.936170 (-1600 2150);
PAINT GREEN (-1600 2150);
DISPLAY INVISIBLE (-1600 2150);
FORCEADD TAP..6
R 2
(-1600 2200);
FORCEPROP 3 LASTPIN (-1650 2200) SIG_NAME M_A_DQ<18>
J 0
(-1640 2210);
DISPLAY 0.659574 (-1640 2210);
PAINT MONO (-1640 2210);
DISPLAY INVISIBLE (-1640 2210);
FORCEPROP 1 LASTPIN (-1650 2200) BN 18
J 2
(-1600 2210);
DISPLAY 0.617021 (-1600 2210);
PAINT PINK (-1600 2210);
FORCEPROP 2 LAST CDS_LIB mstr_standard
J 2
(-1600 2200);
DISPLAY 0.787234 (-1600 2200);
PAINT MONO (-1600 2200);
DISPLAY INVISIBLE (-1600 2200);
FORCEPROP 1 LAST BODY_TYPE PLUMBING
J 2
(-1600 2150);
DISPLAY 1.234043 (-1600 2150);
PAINT GREEN (-1600 2150);
DISPLAY INVISIBLE (-1600 2150);
FORCEPROP 1 LAST HDL_TAP TRUE
J 2
(-1925 2075);
DISPLAY 1.234043 (-1925 2075);
PAINT GREEN (-1925 2075);
DISPLAY INVISIBLE (-1925 2075);
FORCEPROP 1 LAST PATH I166
J 2
(-1600 2200);
DISPLAY 0.936170 (-1600 2200);
PAINT GREEN (-1600 2200);
DISPLAY INVISIBLE (-1600 2200);
FORCEADD TAP..6
R 2
(-1600 2300);
FORCEPROP 3 LASTPIN (-1650 2300) SIG_NAME M_A_DQ<20>
J 0
(-1640 2310);
DISPLAY 0.659574 (-1640 2310);
PAINT MONO (-1640 2310);
DISPLAY INVISIBLE (-1640 2310);
FORCEPROP 1 LASTPIN (-1650 2300) BN 20
J 2
(-1600 2310);
DISPLAY 0.617021 (-1600 2310);
PAINT PINK (-1600 2310);
FORCEPROP 2 LAST CDS_LIB mstr_standard
J 2
(-1600 2300);
DISPLAY 0.787234 (-1600 2300);
PAINT MONO (-1600 2300);
DISPLAY INVISIBLE (-1600 2300);
FORCEPROP 1 LAST BODY_TYPE PLUMBING
J 2
(-1600 2250);
DISPLAY 1.234043 (-1600 2250);
PAINT GREEN (-1600 2250);
DISPLAY INVISIBLE (-1600 2250);
FORCEPROP 1 LAST HDL_TAP TRUE
J 2
(-1925 2175);
DISPLAY 1.234043 (-1925 2175);
PAINT GREEN (-1925 2175);
DISPLAY INVISIBLE (-1925 2175);
FORCEPROP 1 LAST PATH I167
J 2
(-1600 2300);
DISPLAY 0.936170 (-1600 2300);
PAINT GREEN (-1600 2300);
DISPLAY INVISIBLE (-1600 2300);
FORCEADD TAP..6
R 2
(-1600 2250);
FORCEPROP 3 LASTPIN (-1650 2250) SIG_NAME M_A_DQ<21>
J 0
(-1640 2260);
DISPLAY 0.659574 (-1640 2260);
PAINT MONO (-1640 2260);
DISPLAY INVISIBLE (-1640 2260);
FORCEPROP 1 LASTPIN (-1650 2250) BN 21
J 2
(-1600 2260);
DISPLAY 0.617021 (-1600 2260);
PAINT PINK (-1600 2260);
FORCEPROP 2 LAST CDS_LIB mstr_standard
J 2
(-1600 2250);
DISPLAY 0.787234 (-1600 2250);
PAINT MONO (-1600 2250);
DISPLAY INVISIBLE (-1600 2250);
FORCEPROP 1 LAST BODY_TYPE PLUMBING
J 2
(-1600 2200);
DISPLAY 1.234043 (-1600 2200);
PAINT GREEN (-1600 2200);
DISPLAY INVISIBLE (-1600 2200);
FORCEPROP 1 LAST HDL_TAP TRUE
J 2
(-1925 2125);
DISPLAY 1.234043 (-1925 2125);
PAINT GREEN (-1925 2125);
DISPLAY INVISIBLE (-1925 2125);
FORCEPROP 1 LAST PATH I168
J 2
(-1600 2250);
DISPLAY 0.936170 (-1600 2250);
PAINT GREEN (-1600 2250);
DISPLAY INVISIBLE (-1600 2250);
FORCEADD TAP..6
R 2
(-1600 2350);
FORCEPROP 3 LASTPIN (-1650 2350) SIG_NAME M_A_DQ<23>
J 0
(-1640 2360);
DISPLAY 0.659574 (-1640 2360);
PAINT MONO (-1640 2360);
DISPLAY INVISIBLE (-1640 2360);
FORCEPROP 1 LASTPIN (-1650 2350) BN 23
J 2
(-1600 2360);
DISPLAY 0.617021 (-1600 2360);
PAINT PINK (-1600 2360);
FORCEPROP 2 LAST CDS_LIB mstr_standard
J 2
(-1600 2350);
DISPLAY 0.787234 (-1600 2350);
PAINT MONO (-1600 2350);
DISPLAY INVISIBLE (-1600 2350);
FORCEPROP 1 LAST BODY_TYPE PLUMBING
J 2
(-1600 2300);
DISPLAY 1.234043 (-1600 2300);
PAINT GREEN (-1600 2300);
DISPLAY INVISIBLE (-1600 2300);
FORCEPROP 1 LAST HDL_TAP TRUE
J 2
(-1925 2225);
DISPLAY 1.234043 (-1925 2225);
PAINT GREEN (-1925 2225);
DISPLAY INVISIBLE (-1925 2225);
FORCEPROP 1 LAST PATH I169
J 2
(-1600 2350);
DISPLAY 0.936170 (-1600 2350);
PAINT GREEN (-1600 2350);
DISPLAY INVISIBLE (-1600 2350);
FORCEADD TAP..6
R 2
(-1600 2400);
FORCEPROP 3 LASTPIN (-1650 2400) SIG_NAME M_A_DQ<22>
J 0
(-1640 2410);
DISPLAY 0.659574 (-1640 2410);
PAINT MONO (-1640 2410);
DISPLAY INVISIBLE (-1640 2410);
FORCEPROP 1 LASTPIN (-1650 2400) BN 22
J 2
(-1600 2410);
DISPLAY 0.617021 (-1600 2410);
PAINT PINK (-1600 2410);
FORCEPROP 2 LAST CDS_LIB mstr_standard
J 2
(-1600 2400);
DISPLAY 0.787234 (-1600 2400);
PAINT MONO (-1600 2400);
DISPLAY INVISIBLE (-1600 2400);
FORCEPROP 1 LAST BODY_TYPE PLUMBING
J 2
(-1600 2350);
DISPLAY 1.234043 (-1600 2350);
PAINT GREEN (-1600 2350);
DISPLAY INVISIBLE (-1600 2350);
FORCEPROP 1 LAST HDL_TAP TRUE
J 2
(-1925 2275);
DISPLAY 1.234043 (-1925 2275);
PAINT GREEN (-1925 2275);
DISPLAY INVISIBLE (-1925 2275);
FORCEPROP 1 LAST PATH I170
J 2
(-1600 2400);
DISPLAY 0.936170 (-1600 2400);
PAINT GREEN (-1600 2400);
DISPLAY INVISIBLE (-1600 2400);
FORCEADD TAP..6
R 2
(-1600 2500);
FORCEPROP 3 LASTPIN (-1650 2500) SIG_NAME M_A_DQ<24>
J 0
(-1640 2510);
DISPLAY 0.659574 (-1640 2510);
PAINT MONO (-1640 2510);
DISPLAY INVISIBLE (-1640 2510);
FORCEPROP 1 LASTPIN (-1650 2500) BN 24
J 2
(-1600 2510);
DISPLAY 0.617021 (-1600 2510);
PAINT PINK (-1600 2510);
FORCEPROP 2 LAST CDS_LIB mstr_standard
J 2
(-1600 2500);
DISPLAY 0.787234 (-1600 2500);
PAINT MONO (-1600 2500);
DISPLAY INVISIBLE (-1600 2500);
FORCEPROP 1 LAST BODY_TYPE PLUMBING
J 2
(-1600 2450);
DISPLAY 1.234043 (-1600 2450);
PAINT GREEN (-1600 2450);
DISPLAY INVISIBLE (-1600 2450);
FORCEPROP 1 LAST HDL_TAP TRUE
J 2
(-1925 2375);
DISPLAY 1.234043 (-1925 2375);
PAINT GREEN (-1925 2375);
DISPLAY INVISIBLE (-1925 2375);
FORCEPROP 1 LAST PATH I171
J 2
(-1600 2500);
DISPLAY 0.936170 (-1600 2500);
PAINT GREEN (-1600 2500);
DISPLAY INVISIBLE (-1600 2500);
FORCEADD TAP..6
R 2
(-1600 2450);
FORCEPROP 3 LASTPIN (-1650 2450) SIG_NAME M_A_DQ<25>
J 0
(-1640 2460);
DISPLAY 0.659574 (-1640 2460);
PAINT MONO (-1640 2460);
DISPLAY INVISIBLE (-1640 2460);
FORCEPROP 1 LASTPIN (-1650 2450) BN 25
J 2
(-1600 2460);
DISPLAY 0.617021 (-1600 2460);
PAINT PINK (-1600 2460);
FORCEPROP 2 LAST CDS_LIB mstr_standard
J 2
(-1600 2450);
DISPLAY 0.787234 (-1600 2450);
PAINT MONO (-1600 2450);
DISPLAY INVISIBLE (-1600 2450);
FORCEPROP 1 LAST BODY_TYPE PLUMBING
J 2
(-1600 2400);
DISPLAY 1.234043 (-1600 2400);
PAINT GREEN (-1600 2400);
DISPLAY INVISIBLE (-1600 2400);
FORCEPROP 1 LAST HDL_TAP TRUE
J 2
(-1925 2325);
DISPLAY 1.234043 (-1925 2325);
PAINT GREEN (-1925 2325);
DISPLAY INVISIBLE (-1925 2325);
FORCEPROP 1 LAST PATH I172
J 2
(-1600 2450);
DISPLAY 0.936170 (-1600 2450);
PAINT GREEN (-1600 2450);
DISPLAY INVISIBLE (-1600 2450);
FORCEADD TAP..6
R 2
(-1600 2550);
FORCEPROP 3 LASTPIN (-1650 2550) SIG_NAME M_A_DQ<27>
J 0
(-1640 2560);
DISPLAY 0.659574 (-1640 2560);
PAINT MONO (-1640 2560);
DISPLAY INVISIBLE (-1640 2560);
FORCEPROP 1 LASTPIN (-1650 2550) BN 27
J 2
(-1600 2560);
DISPLAY 0.617021 (-1600 2560);
PAINT PINK (-1600 2560);
FORCEPROP 2 LAST CDS_LIB mstr_standard
J 2
(-1600 2550);
DISPLAY 0.787234 (-1600 2550);
PAINT MONO (-1600 2550);
DISPLAY INVISIBLE (-1600 2550);
FORCEPROP 1 LAST BODY_TYPE PLUMBING
J 2
(-1600 2500);
DISPLAY 1.234043 (-1600 2500);
PAINT GREEN (-1600 2500);
DISPLAY INVISIBLE (-1600 2500);
FORCEPROP 1 LAST HDL_TAP TRUE
J 2
(-1925 2425);
DISPLAY 1.234043 (-1925 2425);
PAINT GREEN (-1925 2425);
DISPLAY INVISIBLE (-1925 2425);
FORCEPROP 1 LAST PATH I173
J 2
(-1600 2550);
DISPLAY 0.936170 (-1600 2550);
PAINT GREEN (-1600 2550);
DISPLAY INVISIBLE (-1600 2550);
FORCEADD TAP..6
R 2
(-1600 2600);
FORCEPROP 3 LASTPIN (-1650 2600) SIG_NAME M_A_DQ<26>
J 0
(-1640 2610);
DISPLAY 0.659574 (-1640 2610);
PAINT MONO (-1640 2610);
DISPLAY INVISIBLE (-1640 2610);
FORCEPROP 1 LASTPIN (-1650 2600) BN 26
J 2
(-1600 2610);
DISPLAY 0.617021 (-1600 2610);
PAINT PINK (-1600 2610);
FORCEPROP 2 LAST CDS_LIB mstr_standard
J 2
(-1600 2600);
DISPLAY 0.787234 (-1600 2600);
PAINT MONO (-1600 2600);
DISPLAY INVISIBLE (-1600 2600);
FORCEPROP 1 LAST BODY_TYPE PLUMBING
J 2
(-1600 2550);
DISPLAY 1.234043 (-1600 2550);
PAINT GREEN (-1600 2550);
DISPLAY INVISIBLE (-1600 2550);
FORCEPROP 1 LAST HDL_TAP TRUE
J 2
(-1925 2475);
DISPLAY 1.234043 (-1925 2475);
PAINT GREEN (-1925 2475);
DISPLAY INVISIBLE (-1925 2475);
FORCEPROP 1 LAST PATH I174
J 2
(-1600 2600);
DISPLAY 0.936170 (-1600 2600);
PAINT GREEN (-1600 2600);
DISPLAY INVISIBLE (-1600 2600);
FORCEADD TAP..6
R 2
(-1600 2650);
FORCEPROP 3 LASTPIN (-1650 2650) SIG_NAME M_A_DQ<29>
J 0
(-1640 2660);
DISPLAY 0.659574 (-1640 2660);
PAINT MONO (-1640 2660);
DISPLAY INVISIBLE (-1640 2660);
FORCEPROP 1 LASTPIN (-1650 2650) BN 29
J 2
(-1600 2660);
DISPLAY 0.617021 (-1600 2660);
PAINT PINK (-1600 2660);
FORCEPROP 2 LAST CDS_LIB mstr_standard
J 2
(-1600 2650);
DISPLAY 0.787234 (-1600 2650);
PAINT MONO (-1600 2650);
DISPLAY INVISIBLE (-1600 2650);
FORCEPROP 1 LAST BODY_TYPE PLUMBING
J 2
(-1600 2600);
DISPLAY 1.234043 (-1600 2600);
PAINT GREEN (-1600 2600);
DISPLAY INVISIBLE (-1600 2600);
FORCEPROP 1 LAST HDL_TAP TRUE
J 2
(-1925 2525);
DISPLAY 1.234043 (-1925 2525);
PAINT GREEN (-1925 2525);
DISPLAY INVISIBLE (-1925 2525);
FORCEPROP 1 LAST PATH I175
J 2
(-1600 2650);
DISPLAY 0.936170 (-1600 2650);
PAINT GREEN (-1600 2650);
DISPLAY INVISIBLE (-1600 2650);
FORCEADD TAP..6
R 2
(-1600 1700);
FORCEPROP 3 LASTPIN (-1650 1700) SIG_NAME M_A_DQ<8>
J 0
(-1640 1710);
DISPLAY 0.659574 (-1640 1710);
PAINT MONO (-1640 1710);
DISPLAY INVISIBLE (-1640 1710);
FORCEPROP 1 LASTPIN (-1650 1700) BN 8
J 2
(-1600 1710);
DISPLAY 0.617021 (-1600 1710);
PAINT PINK (-1600 1710);
FORCEPROP 2 LAST CDS_LIB mstr_standard
J 2
(-1600 1700);
DISPLAY 0.787234 (-1600 1700);
PAINT MONO (-1600 1700);
DISPLAY INVISIBLE (-1600 1700);
FORCEPROP 1 LAST BODY_TYPE PLUMBING
J 2
(-1600 1650);
DISPLAY 1.234043 (-1600 1650);
PAINT GREEN (-1600 1650);
DISPLAY INVISIBLE (-1600 1650);
FORCEPROP 1 LAST HDL_TAP TRUE
J 2
(-1925 1575);
DISPLAY 1.234043 (-1925 1575);
PAINT GREEN (-1925 1575);
DISPLAY INVISIBLE (-1925 1575);
FORCEPROP 1 LAST PATH I176
J 2
(-1600 1700);
DISPLAY 0.936170 (-1600 1700);
PAINT GREEN (-1600 1700);
DISPLAY INVISIBLE (-1600 1700);
FORCEADD TAP..6
R 2
(-1600 1750);
FORCEPROP 3 LASTPIN (-1650 1750) SIG_NAME M_A_DQ<11>
J 0
(-1640 1760);
DISPLAY 0.659574 (-1640 1760);
PAINT MONO (-1640 1760);
DISPLAY INVISIBLE (-1640 1760);
FORCEPROP 1 LASTPIN (-1650 1750) BN 11
J 2
(-1600 1760);
DISPLAY 0.617021 (-1600 1760);
PAINT PINK (-1600 1760);
FORCEPROP 2 LAST CDS_LIB mstr_standard
J 2
(-1600 1750);
DISPLAY 0.787234 (-1600 1750);
PAINT MONO (-1600 1750);
DISPLAY INVISIBLE (-1600 1750);
FORCEPROP 1 LAST BODY_TYPE PLUMBING
J 2
(-1600 1700);
DISPLAY 1.234043 (-1600 1700);
PAINT GREEN (-1600 1700);
DISPLAY INVISIBLE (-1600 1700);
FORCEPROP 1 LAST HDL_TAP TRUE
J 2
(-1925 1625);
DISPLAY 1.234043 (-1925 1625);
PAINT GREEN (-1925 1625);
DISPLAY INVISIBLE (-1925 1625);
FORCEPROP 1 LAST PATH I177
J 2
(-1600 1750);
DISPLAY 0.936170 (-1600 1750);
PAINT GREEN (-1600 1750);
DISPLAY INVISIBLE (-1600 1750);
FORCEADD TAP..6
R 2
(-1600 1850);
FORCEPROP 3 LASTPIN (-1650 1850) SIG_NAME M_A_DQ<13>
J 0
(-1640 1860);
DISPLAY 0.659574 (-1640 1860);
PAINT MONO (-1640 1860);
DISPLAY INVISIBLE (-1640 1860);
FORCEPROP 1 LASTPIN (-1650 1850) BN 13
J 2
(-1600 1860);
DISPLAY 0.617021 (-1600 1860);
PAINT PINK (-1600 1860);
FORCEPROP 2 LAST CDS_LIB mstr_standard
J 2
(-1600 1850);
DISPLAY 0.787234 (-1600 1850);
PAINT MONO (-1600 1850);
DISPLAY INVISIBLE (-1600 1850);
FORCEPROP 1 LAST BODY_TYPE PLUMBING
J 2
(-1600 1800);
DISPLAY 1.234043 (-1600 1800);
PAINT GREEN (-1600 1800);
DISPLAY INVISIBLE (-1600 1800);
FORCEPROP 1 LAST HDL_TAP TRUE
J 2
(-1925 1725);
DISPLAY 1.234043 (-1925 1725);
PAINT GREEN (-1925 1725);
DISPLAY INVISIBLE (-1925 1725);
FORCEPROP 1 LAST PATH I178
J 2
(-1600 1850);
DISPLAY 0.936170 (-1600 1850);
PAINT GREEN (-1600 1850);
DISPLAY INVISIBLE (-1600 1850);
FORCEADD TAP..6
R 2
(-1600 1800);
FORCEPROP 3 LASTPIN (-1650 1800) SIG_NAME M_A_DQ<10>
J 0
(-1640 1810);
DISPLAY 0.659574 (-1640 1810);
PAINT MONO (-1640 1810);
DISPLAY INVISIBLE (-1640 1810);
FORCEPROP 1 LASTPIN (-1650 1800) BN 10
J 2
(-1600 1810);
DISPLAY 0.617021 (-1600 1810);
PAINT PINK (-1600 1810);
FORCEPROP 2 LAST CDS_LIB mstr_standard
J 2
(-1600 1800);
DISPLAY 0.787234 (-1600 1800);
PAINT MONO (-1600 1800);
DISPLAY INVISIBLE (-1600 1800);
FORCEPROP 1 LAST BODY_TYPE PLUMBING
J 2
(-1600 1750);
DISPLAY 1.234043 (-1600 1750);
PAINT GREEN (-1600 1750);
DISPLAY INVISIBLE (-1600 1750);
FORCEPROP 1 LAST HDL_TAP TRUE
J 2
(-1925 1675);
DISPLAY 1.234043 (-1925 1675);
PAINT GREEN (-1925 1675);
DISPLAY INVISIBLE (-1925 1675);
FORCEPROP 1 LAST PATH I179
J 2
(-1600 1800);
DISPLAY 0.936170 (-1600 1800);
PAINT GREEN (-1600 1800);
DISPLAY INVISIBLE (-1600 1800);
FORCEADD TAP..6
R 2
(-1600 1900);
FORCEPROP 3 LASTPIN (-1650 1900) SIG_NAME M_A_DQ<12>
J 0
(-1640 1910);
DISPLAY 0.659574 (-1640 1910);
PAINT MONO (-1640 1910);
DISPLAY INVISIBLE (-1640 1910);
FORCEPROP 1 LASTPIN (-1650 1900) BN 12
J 2
(-1600 1910);
DISPLAY 0.617021 (-1600 1910);
PAINT PINK (-1600 1910);
FORCEPROP 2 LAST CDS_LIB mstr_standard
J 2
(-1600 1900);
DISPLAY 0.787234 (-1600 1900);
PAINT MONO (-1600 1900);
DISPLAY INVISIBLE (-1600 1900);
FORCEPROP 1 LAST BODY_TYPE PLUMBING
J 2
(-1600 1850);
DISPLAY 1.234043 (-1600 1850);
PAINT GREEN (-1600 1850);
DISPLAY INVISIBLE (-1600 1850);
FORCEPROP 1 LAST HDL_TAP TRUE
J 2
(-1925 1775);
DISPLAY 1.234043 (-1925 1775);
PAINT GREEN (-1925 1775);
DISPLAY INVISIBLE (-1925 1775);
FORCEPROP 1 LAST PATH I180
J 2
(-1600 1900);
DISPLAY 0.936170 (-1600 1900);
PAINT GREEN (-1600 1900);
DISPLAY INVISIBLE (-1600 1900);
FORCEADD TAP..6
R 2
(-1600 1950);
FORCEPROP 3 LASTPIN (-1650 1950) SIG_NAME M_A_DQ<15>
J 0
(-1640 1960);
DISPLAY 0.659574 (-1640 1960);
PAINT MONO (-1640 1960);
DISPLAY INVISIBLE (-1640 1960);
FORCEPROP 1 LASTPIN (-1650 1950) BN 15
J 2
(-1600 1960);
DISPLAY 0.617021 (-1600 1960);
PAINT PINK (-1600 1960);
FORCEPROP 2 LAST CDS_LIB mstr_standard
J 2
(-1600 1950);
DISPLAY 0.787234 (-1600 1950);
PAINT MONO (-1600 1950);
DISPLAY INVISIBLE (-1600 1950);
FORCEPROP 1 LAST BODY_TYPE PLUMBING
J 2
(-1600 1900);
DISPLAY 1.234043 (-1600 1900);
PAINT GREEN (-1600 1900);
DISPLAY INVISIBLE (-1600 1900);
FORCEPROP 1 LAST HDL_TAP TRUE
J 2
(-1925 1825);
DISPLAY 1.234043 (-1925 1825);
PAINT GREEN (-1925 1825);
DISPLAY INVISIBLE (-1925 1825);
FORCEPROP 1 LAST PATH I181
J 2
(-1600 1950);
DISPLAY 0.936170 (-1600 1950);
PAINT GREEN (-1600 1950);
DISPLAY INVISIBLE (-1600 1950);
FORCEADD TAP..6
R 2
(-1600 1650);
FORCEPROP 3 LASTPIN (-1650 1650) SIG_NAME M_A_DQ<9>
J 0
(-1640 1660);
DISPLAY 0.659574 (-1640 1660);
PAINT MONO (-1640 1660);
DISPLAY INVISIBLE (-1640 1660);
FORCEPROP 1 LASTPIN (-1650 1650) BN 9
J 2
(-1600 1660);
DISPLAY 0.617021 (-1600 1660);
PAINT PINK (-1600 1660);
FORCEPROP 2 LAST CDS_LIB mstr_standard
J 2
(-1600 1650);
DISPLAY 0.787234 (-1600 1650);
PAINT MONO (-1600 1650);
DISPLAY INVISIBLE (-1600 1650);
FORCEPROP 1 LAST BODY_TYPE PLUMBING
J 2
(-1600 1600);
DISPLAY 1.234043 (-1600 1600);
PAINT GREEN (-1600 1600);
DISPLAY INVISIBLE (-1600 1600);
FORCEPROP 1 LAST HDL_TAP TRUE
J 2
(-1925 1525);
DISPLAY 1.234043 (-1925 1525);
PAINT GREEN (-1925 1525);
DISPLAY INVISIBLE (-1925 1525);
FORCEPROP 1 LAST PATH I182
J 2
(-1600 1650);
DISPLAY 0.936170 (-1600 1650);
PAINT GREEN (-1600 1650);
DISPLAY INVISIBLE (-1600 1650);
FORCEADD TAP..6
R 2
(-1600 1250);
FORCEPROP 3 LASTPIN (-1650 1250) SIG_NAME M_A_DQ<1>
J 0
(-1640 1260);
DISPLAY 0.659574 (-1640 1260);
PAINT MONO (-1640 1260);
DISPLAY INVISIBLE (-1640 1260);
FORCEPROP 1 LASTPIN (-1650 1250) BN 1
J 2
(-1600 1260);
DISPLAY 0.617021 (-1600 1260);
PAINT PINK (-1600 1260);
FORCEPROP 2 LAST CDS_LIB mstr_standard
J 2
(-1600 1250);
DISPLAY 0.787234 (-1600 1250);
PAINT MONO (-1600 1250);
DISPLAY INVISIBLE (-1600 1250);
FORCEPROP 1 LAST BODY_TYPE PLUMBING
J 2
(-1600 1200);
DISPLAY 1.234043 (-1600 1200);
PAINT GREEN (-1600 1200);
DISPLAY INVISIBLE (-1600 1200);
FORCEPROP 1 LAST HDL_TAP TRUE
J 2
(-1925 1125);
DISPLAY 1.234043 (-1925 1125);
PAINT GREEN (-1925 1125);
DISPLAY INVISIBLE (-1925 1125);
FORCEPROP 1 LAST PATH I183
J 2
(-1600 1250);
DISPLAY 0.936170 (-1600 1250);
PAINT GREEN (-1600 1250);
DISPLAY INVISIBLE (-1600 1250);
FORCEADD TAP..6
R 2
(-1600 1350);
FORCEPROP 3 LASTPIN (-1650 1350) SIG_NAME M_A_DQ<3>
J 0
(-1640 1360);
DISPLAY 0.659574 (-1640 1360);
PAINT MONO (-1640 1360);
DISPLAY INVISIBLE (-1640 1360);
FORCEPROP 1 LASTPIN (-1650 1350) BN 3
J 2
(-1600 1360);
DISPLAY 0.617021 (-1600 1360);
PAINT PINK (-1600 1360);
FORCEPROP 2 LAST CDS_LIB mstr_standard
J 2
(-1600 1350);
DISPLAY 0.787234 (-1600 1350);
PAINT MONO (-1600 1350);
DISPLAY INVISIBLE (-1600 1350);
FORCEPROP 1 LAST BODY_TYPE PLUMBING
J 2
(-1600 1300);
DISPLAY 1.234043 (-1600 1300);
PAINT GREEN (-1600 1300);
DISPLAY INVISIBLE (-1600 1300);
FORCEPROP 1 LAST HDL_TAP TRUE
J 2
(-1925 1225);
DISPLAY 1.234043 (-1925 1225);
PAINT GREEN (-1925 1225);
DISPLAY INVISIBLE (-1925 1225);
FORCEPROP 1 LAST PATH I184
J 2
(-1600 1350);
DISPLAY 0.936170 (-1600 1350);
PAINT GREEN (-1600 1350);
DISPLAY INVISIBLE (-1600 1350);
FORCEADD TAP..6
R 2
(-1600 1300);
FORCEPROP 3 LASTPIN (-1650 1300) SIG_NAME M_A_DQ<0>
J 0
(-1640 1310);
DISPLAY 0.659574 (-1640 1310);
PAINT MONO (-1640 1310);
DISPLAY INVISIBLE (-1640 1310);
FORCEPROP 1 LASTPIN (-1650 1300) BN 0
J 2
(-1600 1310);
DISPLAY 0.617021 (-1600 1310);
PAINT PINK (-1600 1310);
FORCEPROP 2 LAST CDS_LIB mstr_standard
J 2
(-1600 1300);
DISPLAY 0.787234 (-1600 1300);
PAINT MONO (-1600 1300);
DISPLAY INVISIBLE (-1600 1300);
FORCEPROP 1 LAST BODY_TYPE PLUMBING
J 2
(-1600 1250);
DISPLAY 1.234043 (-1600 1250);
PAINT GREEN (-1600 1250);
DISPLAY INVISIBLE (-1600 1250);
FORCEPROP 1 LAST HDL_TAP TRUE
J 2
(-1925 1175);
DISPLAY 1.234043 (-1925 1175);
PAINT GREEN (-1925 1175);
DISPLAY INVISIBLE (-1925 1175);
FORCEPROP 1 LAST PATH I185
J 2
(-1600 1300);
DISPLAY 0.936170 (-1600 1300);
PAINT GREEN (-1600 1300);
DISPLAY INVISIBLE (-1600 1300);
FORCEADD TAP..6
R 2
(-1600 1400);
FORCEPROP 3 LASTPIN (-1650 1400) SIG_NAME M_A_DQ<2>
J 0
(-1640 1410);
DISPLAY 0.659574 (-1640 1410);
PAINT MONO (-1640 1410);
DISPLAY INVISIBLE (-1640 1410);
FORCEPROP 1 LASTPIN (-1650 1400) BN 2
J 2
(-1600 1410);
DISPLAY 0.617021 (-1600 1410);
PAINT PINK (-1600 1410);
FORCEPROP 2 LAST CDS_LIB mstr_standard
J 2
(-1600 1400);
DISPLAY 0.787234 (-1600 1400);
PAINT MONO (-1600 1400);
DISPLAY INVISIBLE (-1600 1400);
FORCEPROP 1 LAST BODY_TYPE PLUMBING
J 2
(-1600 1350);
DISPLAY 1.234043 (-1600 1350);
PAINT GREEN (-1600 1350);
DISPLAY INVISIBLE (-1600 1350);
FORCEPROP 1 LAST HDL_TAP TRUE
J 2
(-1925 1275);
DISPLAY 1.234043 (-1925 1275);
PAINT GREEN (-1925 1275);
DISPLAY INVISIBLE (-1925 1275);
FORCEPROP 1 LAST PATH I186
J 2
(-1600 1400);
DISPLAY 0.936170 (-1600 1400);
PAINT GREEN (-1600 1400);
DISPLAY INVISIBLE (-1600 1400);
FORCEADD TAP..6
R 2
(-1600 1450);
FORCEPROP 3 LASTPIN (-1650 1450) SIG_NAME M_A_DQ<5>
J 0
(-1640 1460);
DISPLAY 0.659574 (-1640 1460);
PAINT MONO (-1640 1460);
DISPLAY INVISIBLE (-1640 1460);
FORCEPROP 1 LASTPIN (-1650 1450) BN 5
J 2
(-1600 1460);
DISPLAY 0.617021 (-1600 1460);
PAINT PINK (-1600 1460);
FORCEPROP 2 LAST CDS_LIB mstr_standard
J 2
(-1600 1450);
DISPLAY 0.787234 (-1600 1450);
PAINT MONO (-1600 1450);
DISPLAY INVISIBLE (-1600 1450);
FORCEPROP 1 LAST BODY_TYPE PLUMBING
J 2
(-1600 1400);
DISPLAY 1.234043 (-1600 1400);
PAINT GREEN (-1600 1400);
DISPLAY INVISIBLE (-1600 1400);
FORCEPROP 1 LAST HDL_TAP TRUE
J 2
(-1925 1325);
DISPLAY 1.234043 (-1925 1325);
PAINT GREEN (-1925 1325);
DISPLAY INVISIBLE (-1925 1325);
FORCEPROP 1 LAST PATH I187
J 2
(-1600 1450);
DISPLAY 0.936170 (-1600 1450);
PAINT GREEN (-1600 1450);
DISPLAY INVISIBLE (-1600 1450);
FORCEADD TAP..6
R 2
(-1600 1500);
FORCEPROP 3 LASTPIN (-1650 1500) SIG_NAME M_A_DQ<4>
J 0
(-1640 1510);
DISPLAY 0.659574 (-1640 1510);
PAINT MONO (-1640 1510);
DISPLAY INVISIBLE (-1640 1510);
FORCEPROP 1 LASTPIN (-1650 1500) BN 4
J 2
(-1600 1510);
DISPLAY 0.617021 (-1600 1510);
PAINT PINK (-1600 1510);
FORCEPROP 2 LAST CDS_LIB mstr_standard
J 2
(-1600 1500);
DISPLAY 0.787234 (-1600 1500);
PAINT MONO (-1600 1500);
DISPLAY INVISIBLE (-1600 1500);
FORCEPROP 1 LAST BODY_TYPE PLUMBING
J 2
(-1600 1450);
DISPLAY 1.234043 (-1600 1450);
PAINT GREEN (-1600 1450);
DISPLAY INVISIBLE (-1600 1450);
FORCEPROP 1 LAST HDL_TAP TRUE
J 2
(-1925 1375);
DISPLAY 1.234043 (-1925 1375);
PAINT GREEN (-1925 1375);
DISPLAY INVISIBLE (-1925 1375);
FORCEPROP 1 LAST PATH I188
J 2
(-1600 1500);
DISPLAY 0.936170 (-1600 1500);
PAINT GREEN (-1600 1500);
DISPLAY INVISIBLE (-1600 1500);
FORCEADD TAP..6
R 2
(-1600 1600);
FORCEPROP 3 LASTPIN (-1650 1600) SIG_NAME M_A_DQ<6>
J 0
(-1640 1610);
DISPLAY 0.659574 (-1640 1610);
PAINT MONO (-1640 1610);
DISPLAY INVISIBLE (-1640 1610);
FORCEPROP 1 LASTPIN (-1650 1600) BN 6
J 2
(-1600 1610);
DISPLAY 0.617021 (-1600 1610);
PAINT PINK (-1600 1610);
FORCEPROP 2 LAST CDS_LIB mstr_standard
J 2
(-1600 1600);
DISPLAY 0.787234 (-1600 1600);
PAINT MONO (-1600 1600);
DISPLAY INVISIBLE (-1600 1600);
FORCEPROP 1 LAST BODY_TYPE PLUMBING
J 2
(-1600 1550);
DISPLAY 1.234043 (-1600 1550);
PAINT GREEN (-1600 1550);
DISPLAY INVISIBLE (-1600 1550);
FORCEPROP 1 LAST HDL_TAP TRUE
J 2
(-1925 1475);
DISPLAY 1.234043 (-1925 1475);
PAINT GREEN (-1925 1475);
DISPLAY INVISIBLE (-1925 1475);
FORCEPROP 1 LAST PATH I189
J 2
(-1600 1600);
DISPLAY 0.936170 (-1600 1600);
PAINT GREEN (-1600 1600);
DISPLAY INVISIBLE (-1600 1600);
FORCEADD TAP..6
R 2
(-1600 1550);
FORCEPROP 3 LASTPIN (-1650 1550) SIG_NAME M_A_DQ<7>
J 0
(-1640 1560);
DISPLAY 0.659574 (-1640 1560);
PAINT MONO (-1640 1560);
DISPLAY INVISIBLE (-1640 1560);
FORCEPROP 1 LASTPIN (-1650 1550) BN 7
J 2
(-1600 1560);
DISPLAY 0.617021 (-1600 1560);
PAINT PINK (-1600 1560);
FORCEPROP 2 LAST CDS_LIB mstr_standard
J 2
(-1600 1550);
DISPLAY 0.787234 (-1600 1550);
PAINT MONO (-1600 1550);
DISPLAY INVISIBLE (-1600 1550);
FORCEPROP 1 LAST BODY_TYPE PLUMBING
J 2
(-1600 1500);
DISPLAY 1.234043 (-1600 1500);
PAINT GREEN (-1600 1500);
DISPLAY INVISIBLE (-1600 1500);
FORCEPROP 1 LAST HDL_TAP TRUE
J 2
(-1925 1425);
DISPLAY 1.234043 (-1925 1425);
PAINT GREEN (-1925 1425);
DISPLAY INVISIBLE (-1925 1425);
FORCEPROP 1 LAST PATH I190
J 2
(-1600 1550);
DISPLAY 0.936170 (-1600 1550);
PAINT GREEN (-1600 1550);
DISPLAY INVISIBLE (-1600 1550);
FORCEADD OFFPAGE..3
(-1000 4450);
FORCEPROP 2 LAST $XR0 23 
J 0
(-786 4450);
DISPLAY 0.638298 (-786 4450);
PAINT MONO (-786 4450);
FORCEPROP 2 LAST $XR1 44 
J 0
(-696 4450);
DISPLAY 0.638298 (-696 4450);
PAINT MONO (-696 4450);
FORCEPROP 2 LAST CDS_LIB mstr_standard
J 0
(-1000 4450);
DISPLAY 0.787234 (-1000 4450);
PAINT MONO (-1000 4450);
DISPLAY INVISIBLE (-1000 4450);
FORCEPROP 1 LAST OFFPAGE TRUE
J 0
(-675 4325);
DISPLAY 0.936170 (-675 4325);
PAINT GREEN (-675 4325);
DISPLAY INVISIBLE (-675 4325);
FORCEPROP 1 LAST COMMENT_BODY TRUE
J 0
(-1050 4350);
DISPLAY 0.936170 (-1050 4350);
PAINT GREEN (-1050 4350);
DISPLAY INVISIBLE (-1050 4350);
FORCEPROP 2 LAST PATH I191
J 0
(-950 4525);
DISPLAY 0.787234 (-950 4525);
PAINT MONO (-950 4525);
DISPLAY INVISIBLE (-950 4525);
FORCEADD TAP..6
R 2
(650 4200);
FORCEPROP 3 LASTPIN (600 4200) SIG_NAME M_A_DQS_DP<10>
J 0
(610 4210);
DISPLAY 0.659574 (610 4210);
PAINT MONO (610 4210);
DISPLAY INVISIBLE (610 4210);
FORCEPROP 1 LASTPIN (600 4200) BN 10
J 2
(650 4210);
DISPLAY 0.617021 (650 4210);
PAINT PINK (650 4210);
FORCEPROP 2 LAST CDS_LIB mstr_standard
J 0
(650 4200);
DISPLAY 0.787234 (650 4200);
PAINT MONO (650 4200);
DISPLAY INVISIBLE (650 4200);
FORCEPROP 1 LAST BODY_TYPE PLUMBING
J 2
(650 4150);
DISPLAY 1.234043 (650 4150);
PAINT GREEN (650 4150);
DISPLAY INVISIBLE (650 4150);
FORCEPROP 1 LAST HDL_TAP TRUE
J 2
(325 4075);
DISPLAY 1.234043 (325 4075);
PAINT GREEN (325 4075);
DISPLAY INVISIBLE (325 4075);
FORCEPROP 1 LAST PATH I192
J 2
(650 4200);
DISPLAY 0.936170 (650 4200);
PAINT GREEN (650 4200);
DISPLAY INVISIBLE (650 4200);
FORCEADD TAP..6
R 2
(650 4300);
FORCEPROP 3 LASTPIN (600 4300) SIG_NAME M_A_DQS_DP<11>
J 0
(610 4310);
DISPLAY 0.659574 (610 4310);
PAINT MONO (610 4310);
DISPLAY INVISIBLE (610 4310);
FORCEPROP 1 LASTPIN (600 4300) BN 11
J 2
(650 4310);
DISPLAY 0.617021 (650 4310);
PAINT PINK (650 4310);
FORCEPROP 2 LAST CDS_LIB mstr_standard
J 0
(650 4300);
DISPLAY 0.787234 (650 4300);
PAINT MONO (650 4300);
DISPLAY INVISIBLE (650 4300);
FORCEPROP 1 LAST BODY_TYPE PLUMBING
J 2
(650 4250);
DISPLAY 1.234043 (650 4250);
PAINT GREEN (650 4250);
DISPLAY INVISIBLE (650 4250);
FORCEPROP 1 LAST HDL_TAP TRUE
J 2
(325 4175);
DISPLAY 1.234043 (325 4175);
PAINT GREEN (325 4175);
DISPLAY INVISIBLE (325 4175);
FORCEPROP 1 LAST PATH I193
J 2
(650 4300);
DISPLAY 0.936170 (650 4300);
PAINT GREEN (650 4300);
DISPLAY INVISIBLE (650 4300);
FORCEADD TAP..6
R 2
(650 4000);
FORCEPROP 3 LASTPIN (600 4000) SIG_NAME M_A_DQS_DP<8>
J 0
(610 4010);
DISPLAY 0.659574 (610 4010);
PAINT MONO (610 4010);
DISPLAY INVISIBLE (610 4010);
FORCEPROP 1 LASTPIN (600 4000) BN 8
J 2
(650 4010);
DISPLAY 0.617021 (650 4010);
PAINT PINK (650 4010);
FORCEPROP 2 LAST CDS_LIB mstr_standard
J 0
(650 4000);
DISPLAY 0.787234 (650 4000);
PAINT MONO (650 4000);
DISPLAY INVISIBLE (650 4000);
FORCEPROP 1 LAST BODY_TYPE PLUMBING
J 2
(650 3950);
DISPLAY 1.234043 (650 3950);
PAINT GREEN (650 3950);
DISPLAY INVISIBLE (650 3950);
FORCEPROP 1 LAST HDL_TAP TRUE
J 2
(325 3875);
DISPLAY 1.234043 (325 3875);
PAINT GREEN (325 3875);
DISPLAY INVISIBLE (325 3875);
FORCEPROP 1 LAST PATH I194
J 2
(650 4000);
DISPLAY 0.936170 (650 4000);
PAINT GREEN (650 4000);
DISPLAY INVISIBLE (650 4000);
FORCEADD TAP..6
R 2
(650 4100);
FORCEPROP 3 LASTPIN (600 4100) SIG_NAME M_A_DQS_DP<9>
J 0
(610 4110);
DISPLAY 0.659574 (610 4110);
PAINT MONO (610 4110);
DISPLAY INVISIBLE (610 4110);
FORCEPROP 1 LASTPIN (600 4100) BN 9
J 2
(650 4110);
DISPLAY 0.617021 (650 4110);
PAINT PINK (650 4110);
FORCEPROP 2 LAST CDS_LIB mstr_standard
J 0
(650 4100);
DISPLAY 0.787234 (650 4100);
PAINT MONO (650 4100);
DISPLAY INVISIBLE (650 4100);
FORCEPROP 1 LAST BODY_TYPE PLUMBING
J 2
(650 4050);
DISPLAY 1.234043 (650 4050);
PAINT GREEN (650 4050);
DISPLAY INVISIBLE (650 4050);
FORCEPROP 1 LAST HDL_TAP TRUE
J 2
(325 3975);
DISPLAY 1.234043 (325 3975);
PAINT GREEN (325 3975);
DISPLAY INVISIBLE (325 3975);
FORCEPROP 1 LAST PATH I195
J 2
(650 4100);
DISPLAY 0.936170 (650 4100);
PAINT GREEN (650 4100);
DISPLAY INVISIBLE (650 4100);
FORCEADD TAP..6
R 2
(650 3700);
FORCEPROP 3 LASTPIN (600 3700) SIG_NAME M_A_DQS_DP<5>
J 0
(610 3710);
DISPLAY 0.659574 (610 3710);
PAINT MONO (610 3710);
DISPLAY INVISIBLE (610 3710);
FORCEPROP 1 LASTPIN (600 3700) BN 5
J 2
(650 3710);
DISPLAY 0.617021 (650 3710);
PAINT PINK (650 3710);
FORCEPROP 2 LAST CDS_LIB mstr_standard
J 0
(650 3700);
DISPLAY 0.787234 (650 3700);
PAINT MONO (650 3700);
DISPLAY INVISIBLE (650 3700);
FORCEPROP 1 LAST BODY_TYPE PLUMBING
J 2
(650 3650);
DISPLAY 1.234043 (650 3650);
PAINT GREEN (650 3650);
DISPLAY INVISIBLE (650 3650);
FORCEPROP 1 LAST HDL_TAP TRUE
J 2
(325 3575);
DISPLAY 1.234043 (325 3575);
PAINT GREEN (325 3575);
DISPLAY INVISIBLE (325 3575);
FORCEPROP 1 LAST PATH I196
J 2
(650 3700);
DISPLAY 0.936170 (650 3700);
PAINT GREEN (650 3700);
DISPLAY INVISIBLE (650 3700);
FORCEADD TAP..6
R 2
(650 3800);
FORCEPROP 3 LASTPIN (600 3800) SIG_NAME M_A_DQS_DP<6>
J 0
(610 3810);
DISPLAY 0.659574 (610 3810);
PAINT MONO (610 3810);
DISPLAY INVISIBLE (610 3810);
FORCEPROP 1 LASTPIN (600 3800) BN 6
J 2
(650 3810);
DISPLAY 0.617021 (650 3810);
PAINT PINK (650 3810);
FORCEPROP 2 LAST CDS_LIB mstr_standard
J 0
(650 3800);
DISPLAY 0.787234 (650 3800);
PAINT MONO (650 3800);
DISPLAY INVISIBLE (650 3800);
FORCEPROP 1 LAST BODY_TYPE PLUMBING
J 2
(650 3750);
DISPLAY 1.234043 (650 3750);
PAINT GREEN (650 3750);
DISPLAY INVISIBLE (650 3750);
FORCEPROP 1 LAST HDL_TAP TRUE
J 2
(325 3675);
DISPLAY 1.234043 (325 3675);
PAINT GREEN (325 3675);
DISPLAY INVISIBLE (325 3675);
FORCEPROP 1 LAST PATH I197
J 2
(650 3800);
DISPLAY 0.936170 (650 3800);
PAINT GREEN (650 3800);
DISPLAY INVISIBLE (650 3800);
FORCEADD TAP..6
R 2
(650 3900);
FORCEPROP 3 LASTPIN (600 3900) SIG_NAME M_A_DQS_DP<7>
J 0
(610 3910);
DISPLAY 0.659574 (610 3910);
PAINT MONO (610 3910);
DISPLAY INVISIBLE (610 3910);
FORCEPROP 1 LASTPIN (600 3900) BN 7
J 2
(650 3910);
DISPLAY 0.617021 (650 3910);
PAINT PINK (650 3910);
FORCEPROP 2 LAST CDS_LIB mstr_standard
J 0
(650 3900);
DISPLAY 0.787234 (650 3900);
PAINT MONO (650 3900);
DISPLAY INVISIBLE (650 3900);
FORCEPROP 1 LAST BODY_TYPE PLUMBING
J 2
(650 3850);
DISPLAY 1.234043 (650 3850);
PAINT GREEN (650 3850);
DISPLAY INVISIBLE (650 3850);
FORCEPROP 1 LAST HDL_TAP TRUE
J 2
(325 3775);
DISPLAY 1.234043 (325 3775);
PAINT GREEN (325 3775);
DISPLAY INVISIBLE (325 3775);
FORCEPROP 1 LAST PATH I198
J 2
(650 3900);
DISPLAY 0.936170 (650 3900);
PAINT GREEN (650 3900);
DISPLAY INVISIBLE (650 3900);
FORCEADD TAP..6
R 2
(650 3500);
FORCEPROP 3 LASTPIN (600 3500) SIG_NAME M_A_DQS_DP<3>
J 0
(610 3510);
DISPLAY 0.659574 (610 3510);
PAINT MONO (610 3510);
DISPLAY INVISIBLE (610 3510);
FORCEPROP 1 LASTPIN (600 3500) BN 3
J 2
(650 3510);
DISPLAY 0.617021 (650 3510);
PAINT PINK (650 3510);
FORCEPROP 2 LAST CDS_LIB mstr_standard
J 0
(650 3500);
DISPLAY 0.787234 (650 3500);
PAINT MONO (650 3500);
DISPLAY INVISIBLE (650 3500);
FORCEPROP 1 LAST BODY_TYPE PLUMBING
J 2
(650 3450);
DISPLAY 1.234043 (650 3450);
PAINT GREEN (650 3450);
DISPLAY INVISIBLE (650 3450);
FORCEPROP 1 LAST HDL_TAP TRUE
J 2
(325 3375);
DISPLAY 1.234043 (325 3375);
PAINT GREEN (325 3375);
DISPLAY INVISIBLE (325 3375);
FORCEPROP 1 LAST PATH I199
J 2
(650 3500);
DISPLAY 0.936170 (650 3500);
PAINT GREEN (650 3500);
DISPLAY INVISIBLE (650 3500);
FORCEADD SCONN288_H44441004..2
(-50 4050);
FORCEPROP 1 LAST LOCATION J4G1
J 0
(-450 5150);
DISPLAY 0.617021 (-450 5150);
PAINT AQUA (-450 5150);
FORCEPROP 1 LAST PART_NUMBER H44441-004
J 0
(-450 2950);
DISPLAY 0.617021 (-450 2950);
PAINT BLUE (-450 2950);
FORCEPROP 1 LAST MATERIAL SCONN
J 0
(-450 5100);
DISPLAY 0.617021 (-450 5100);
PAINT SKYBLUE (-450 5100);
FORCEPROP 2 LASTPIN (400 4900) $PN 51
J 0
(410 4910);
DISPLAY 0.617021 (410 4910);
PAINT ORANGE (410 4910);
FORCEPROP 2 LASTPIN (400 4850) $PN 52
J 0
(410 4860);
DISPLAY 0.617021 (410 4860);
PAINT ORANGE (410 4860);
FORCEPROP 2 LASTPIN (400 4800) $PN 132
J 0
(410 4810);
DISPLAY 0.617021 (410 4810);
PAINT ORANGE (410 4810);
FORCEPROP 2 LASTPIN (400 4750) $PN 133
J 0
(410 4760);
DISPLAY 0.617021 (410 4760);
PAINT ORANGE (410 4760);
FORCEPROP 2 LASTPIN (400 4700) $PN 121
J 0
(410 4710);
DISPLAY 0.617021 (410 4710);
PAINT ORANGE (410 4710);
FORCEPROP 2 LASTPIN (400 4650) $PN 122
J 0
(410 4660);
DISPLAY 0.617021 (410 4660);
PAINT ORANGE (410 4660);
FORCEPROP 2 LASTPIN (400 4600) $PN 110
J 0
(410 4610);
DISPLAY 0.617021 (410 4610);
PAINT ORANGE (410 4610);
FORCEPROP 2 LASTPIN (400 4550) $PN 111
J 0
(410 4560);
DISPLAY 0.617021 (410 4560);
PAINT ORANGE (410 4560);
FORCEPROP 2 LASTPIN (400 4500) $PN 99
J 0
(410 4510);
DISPLAY 0.617021 (410 4510);
PAINT ORANGE (410 4510);
FORCEPROP 2 LASTPIN (400 4450) $PN 100
J 0
(410 4460);
DISPLAY 0.617021 (410 4460);
PAINT ORANGE (410 4460);
FORCEPROP 2 LASTPIN (400 4400) $PN 40
J 0
(410 4410);
DISPLAY 0.617021 (410 4410);
PAINT ORANGE (410 4410);
FORCEPROP 2 LASTPIN (400 4350) $PN 41
J 0
(410 4360);
DISPLAY 0.617021 (410 4360);
PAINT ORANGE (410 4360);
FORCEPROP 2 LASTPIN (400 4300) $PN 29
J 0
(410 4310);
DISPLAY 0.617021 (410 4310);
PAINT ORANGE (410 4310);
FORCEPROP 2 LASTPIN (400 4250) $PN 30
J 0
(410 4260);
DISPLAY 0.617021 (410 4260);
PAINT ORANGE (410 4260);
FORCEPROP 2 LASTPIN (400 4200) $PN 18
J 0
(410 4210);
DISPLAY 0.617021 (410 4210);
PAINT ORANGE (410 4210);
FORCEPROP 2 LASTPIN (400 4150) $PN 19
J 0
(410 4160);
DISPLAY 0.617021 (410 4160);
PAINT ORANGE (410 4160);
FORCEPROP 2 LASTPIN (400 4100) $PN 7
J 0
(410 4110);
DISPLAY 0.617021 (410 4110);
PAINT ORANGE (410 4110);
FORCEPROP 2 LASTPIN (400 4050) $PN 8
J 0
(410 4060);
DISPLAY 0.617021 (410 4060);
PAINT ORANGE (410 4060);
FORCEPROP 2 LASTPIN (400 4000) $PN 197
J 0
(410 4010);
DISPLAY 0.617021 (410 4010);
PAINT ORANGE (410 4010);
FORCEPROP 2 LASTPIN (400 3950) $PN 196
J 0
(410 3960);
DISPLAY 0.617021 (410 3960);
PAINT ORANGE (410 3960);
FORCEPROP 2 LASTPIN (400 3900) $PN 278
J 0
(410 3910);
DISPLAY 0.617021 (410 3910);
PAINT ORANGE (410 3910);
FORCEPROP 2 LASTPIN (400 3850) $PN 277
J 0
(410 3860);
DISPLAY 0.617021 (410 3860);
PAINT ORANGE (410 3860);
FORCEPROP 2 LASTPIN (400 3800) $PN 267
J 0
(410 3810);
DISPLAY 0.617021 (410 3810);
PAINT ORANGE (410 3810);
FORCEPROP 2 LASTPIN (400 3750) $PN 266
J 0
(410 3760);
DISPLAY 0.617021 (410 3760);
PAINT ORANGE (410 3760);
FORCEPROP 2 LASTPIN (400 3700) $PN 256
J 0
(410 3710);
DISPLAY 0.617021 (410 3710);
PAINT ORANGE (410 3710);
FORCEPROP 2 LASTPIN (400 3650) $PN 255
J 0
(410 3660);
DISPLAY 0.617021 (410 3660);
PAINT ORANGE (410 3660);
FORCEPROP 2 LASTPIN (400 3600) $PN 245
J 0
(410 3610);
DISPLAY 0.617021 (410 3610);
PAINT ORANGE (410 3610);
FORCEPROP 2 LASTPIN (400 3550) $PN 244
J 0
(410 3560);
DISPLAY 0.617021 (410 3560);
PAINT ORANGE (410 3560);
FORCEPROP 2 LASTPIN (400 3500) $PN 186
J 0
(410 3510);
DISPLAY 0.617021 (410 3510);
PAINT ORANGE (410 3510);
FORCEPROP 2 LASTPIN (400 3450) $PN 185
J 0
(410 3460);
DISPLAY 0.617021 (410 3460);
PAINT ORANGE (410 3460);
FORCEPROP 2 LASTPIN (400 3400) $PN 175
J 0
(410 3410);
DISPLAY 0.617021 (410 3410);
PAINT ORANGE (410 3410);
FORCEPROP 2 LASTPIN (400 3350) $PN 174
J 0
(410 3360);
DISPLAY 0.617021 (410 3360);
PAINT ORANGE (410 3360);
FORCEPROP 2 LASTPIN (400 3300) $PN 164
J 0
(410 3310);
DISPLAY 0.617021 (410 3310);
PAINT ORANGE (410 3310);
FORCEPROP 2 LASTPIN (400 3250) $PN 163
J 0
(410 3260);
DISPLAY 0.617021 (410 3260);
PAINT ORANGE (410 3260);
FORCEPROP 2 LASTPIN (400 3200) $PN 153
J 0
(410 3210);
DISPLAY 0.617021 (410 3210);
PAINT ORANGE (410 3210);
FORCEPROP 2 LASTPIN (400 3150) $PN 152
J 0
(410 3160);
DISPLAY 0.617021 (410 3160);
PAINT ORANGE (410 3160);
FORCEPROP 1 LAST PACK_TYPE PIP
J 0
(-450 5200);
PAINT SKYBLUE (-450 5200);
DISPLAY INVISIBLE (-450 5200);
FORCEPROP 2 LAST BOM_COST MEM
J 0
(-50 4050);
PAINT ORANGE (-50 4050);
DISPLAY INVISIBLE (-50 4050);
FORCEPROP 2 LAST CDS_LIB mstr_sconn
J 0
(-50 4050);
PAINT ORANGE (-50 4050);
DISPLAY INVISIBLE (-50 4050);
FORCEPROP 2 LAST SEC_TYPE PIP
J 0
(-450 5200);
DISPLAY 1.021277 (-450 5200);
PAINT ORANGE (-450 5200);
DISPLAY INVISIBLE (-450 5200);
FORCEPROP 2 LAST SEC 2
J 0
(-450 5200);
DISPLAY 0.680851 (-450 5200);
PAINT MONO (-450 5200);
DISPLAY INVISIBLE (-450 5200);
FORCEPROP 2 LAST CDS_LOCATION J4G1
J 0
(-450 5150);
DISPLAY 0.617021 (-450 5150);
PAINT AQUA (-450 5150);
DISPLAY INVISIBLE (-450 5150);
FORCEPROP 1 LAST PATH I2
J 0
(-50 5100);
PAINT GREEN (-50 5100);
DISPLAY INVISIBLE (-50 5100);
FORCEPROP 2 LAST ROOM DDR4_CH_A
J 0
(-50 4050);
PAINT ORANGE (-50 4050);
DISPLAY INVISIBLE (-50 4050);
FORCEADD TAP..6
R 2
(650 3600);
FORCEPROP 3 LASTPIN (600 3600) SIG_NAME M_A_DQS_DP<4>
J 0
(610 3610);
DISPLAY 0.659574 (610 3610);
PAINT MONO (610 3610);
DISPLAY INVISIBLE (610 3610);
FORCEPROP 1 LASTPIN (600 3600) BN 4
J 2
(650 3610);
DISPLAY 0.617021 (650 3610);
PAINT PINK (650 3610);
FORCEPROP 2 LAST CDS_LIB mstr_standard
J 0
(650 3600);
DISPLAY 0.787234 (650 3600);
PAINT MONO (650 3600);
DISPLAY INVISIBLE (650 3600);
FORCEPROP 1 LAST BODY_TYPE PLUMBING
J 2
(650 3550);
DISPLAY 1.234043 (650 3550);
PAINT GREEN (650 3550);
DISPLAY INVISIBLE (650 3550);
FORCEPROP 1 LAST HDL_TAP TRUE
J 2
(325 3475);
DISPLAY 1.234043 (325 3475);
PAINT GREEN (325 3475);
DISPLAY INVISIBLE (325 3475);
FORCEPROP 1 LAST PATH I200
J 2
(650 3600);
DISPLAY 0.936170 (650 3600);
PAINT GREEN (650 3600);
DISPLAY INVISIBLE (650 3600);
FORCEADD TAP..6
R 2
(650 3200);
FORCEPROP 3 LASTPIN (600 3200) SIG_NAME M_A_DQS_DP<0>
J 0
(610 3210);
DISPLAY 0.659574 (610 3210);
PAINT MONO (610 3210);
DISPLAY INVISIBLE (610 3210);
FORCEPROP 1 LASTPIN (600 3200) BN 0
J 2
(650 3210);
DISPLAY 0.617021 (650 3210);
PAINT PINK (650 3210);
FORCEPROP 2 LAST CDS_LIB mstr_standard
J 0
(650 3200);
DISPLAY 0.787234 (650 3200);
PAINT MONO (650 3200);
DISPLAY INVISIBLE (650 3200);
FORCEPROP 1 LAST BODY_TYPE PLUMBING
J 2
(650 3150);
DISPLAY 1.234043 (650 3150);
PAINT GREEN (650 3150);
DISPLAY INVISIBLE (650 3150);
FORCEPROP 1 LAST HDL_TAP TRUE
J 2
(325 3075);
DISPLAY 1.234043 (325 3075);
PAINT GREEN (325 3075);
DISPLAY INVISIBLE (325 3075);
FORCEPROP 1 LAST PATH I201
J 2
(650 3200);
DISPLAY 0.936170 (650 3200);
PAINT GREEN (650 3200);
DISPLAY INVISIBLE (650 3200);
FORCEADD TAP..6
R 2
(650 3300);
FORCEPROP 3 LASTPIN (600 3300) SIG_NAME M_A_DQS_DP<1>
J 0
(610 3310);
DISPLAY 0.659574 (610 3310);
PAINT MONO (610 3310);
DISPLAY INVISIBLE (610 3310);
FORCEPROP 1 LASTPIN (600 3300) BN 1
J 2
(650 3310);
DISPLAY 0.617021 (650 3310);
PAINT PINK (650 3310);
FORCEPROP 2 LAST CDS_LIB mstr_standard
J 0
(650 3300);
DISPLAY 0.787234 (650 3300);
PAINT MONO (650 3300);
DISPLAY INVISIBLE (650 3300);
FORCEPROP 1 LAST BODY_TYPE PLUMBING
J 2
(650 3250);
DISPLAY 1.234043 (650 3250);
PAINT GREEN (650 3250);
DISPLAY INVISIBLE (650 3250);
FORCEPROP 1 LAST HDL_TAP TRUE
J 2
(325 3175);
DISPLAY 1.234043 (325 3175);
PAINT GREEN (325 3175);
DISPLAY INVISIBLE (325 3175);
FORCEPROP 1 LAST PATH I202
J 2
(650 3300);
DISPLAY 0.936170 (650 3300);
PAINT GREEN (650 3300);
DISPLAY INVISIBLE (650 3300);
FORCEADD TAP..6
R 2
(650 3400);
FORCEPROP 3 LASTPIN (600 3400) SIG_NAME M_A_DQS_DP<2>
J 0
(610 3410);
DISPLAY 0.659574 (610 3410);
PAINT MONO (610 3410);
DISPLAY INVISIBLE (610 3410);
FORCEPROP 1 LASTPIN (600 3400) BN 2
J 2
(650 3410);
DISPLAY 0.617021 (650 3410);
PAINT PINK (650 3410);
FORCEPROP 2 LAST CDS_LIB mstr_standard
J 0
(650 3400);
DISPLAY 0.787234 (650 3400);
PAINT MONO (650 3400);
DISPLAY INVISIBLE (650 3400);
FORCEPROP 1 LAST BODY_TYPE PLUMBING
J 2
(650 3350);
DISPLAY 1.234043 (650 3350);
PAINT GREEN (650 3350);
DISPLAY INVISIBLE (650 3350);
FORCEPROP 1 LAST HDL_TAP TRUE
J 2
(325 3275);
DISPLAY 1.234043 (325 3275);
PAINT GREEN (325 3275);
DISPLAY INVISIBLE (325 3275);
FORCEPROP 1 LAST PATH I203
J 2
(650 3400);
DISPLAY 0.936170 (650 3400);
PAINT GREEN (650 3400);
DISPLAY INVISIBLE (650 3400);
FORCEADD OFFPAGE..3
(1550 4950);
FORCEPROP 2 LAST $XR0 23 
J 0
(1764 4950);
DISPLAY 0.638298 (1764 4950);
PAINT MONO (1764 4950);
FORCEPROP 2 LAST $XR1 44 
J 0
(1854 4950);
DISPLAY 0.638298 (1854 4950);
PAINT MONO (1854 4950);
FORCEPROP 2 LAST CDS_LIB mstr_standard
J 0
(1550 4950);
DISPLAY 0.787234 (1550 4950);
PAINT MONO (1550 4950);
DISPLAY INVISIBLE (1550 4950);
FORCEPROP 1 LAST OFFPAGE TRUE
J 0
(1875 4825);
DISPLAY 0.936170 (1875 4825);
PAINT GREEN (1875 4825);
DISPLAY INVISIBLE (1875 4825);
FORCEPROP 1 LAST COMMENT_BODY TRUE
J 0
(1500 4850);
DISPLAY 0.936170 (1500 4850);
PAINT GREEN (1500 4850);
DISPLAY INVISIBLE (1500 4850);
FORCEPROP 2 LAST PATH I204
J 0
(1750 5025);
DISPLAY 0.787234 (1750 5025);
PAINT MONO (1750 5025);
DISPLAY INVISIBLE (1750 5025);
FORCEADD TAP..6
R 2
(650 4700);
FORCEPROP 3 LASTPIN (600 4700) SIG_NAME M_A_DQS_DP<15>
J 0
(610 4710);
DISPLAY 0.659574 (610 4710);
PAINT MONO (610 4710);
DISPLAY INVISIBLE (610 4710);
FORCEPROP 1 LASTPIN (600 4700) BN 15
J 2
(650 4710);
DISPLAY 0.617021 (650 4710);
PAINT PINK (650 4710);
FORCEPROP 2 LAST CDS_LIB mstr_standard
J 0
(650 4700);
DISPLAY 0.787234 (650 4700);
PAINT MONO (650 4700);
DISPLAY INVISIBLE (650 4700);
FORCEPROP 1 LAST BODY_TYPE PLUMBING
J 2
(650 4650);
DISPLAY 1.234043 (650 4650);
PAINT GREEN (650 4650);
DISPLAY INVISIBLE (650 4650);
FORCEPROP 1 LAST HDL_TAP TRUE
J 2
(325 4575);
DISPLAY 1.234043 (325 4575);
PAINT GREEN (325 4575);
DISPLAY INVISIBLE (325 4575);
FORCEPROP 1 LAST PATH I205
J 2
(650 4700);
DISPLAY 0.936170 (650 4700);
PAINT GREEN (650 4700);
DISPLAY INVISIBLE (650 4700);
FORCEADD TAP..6
R 2
(650 4900);
FORCEPROP 3 LASTPIN (600 4900) SIG_NAME M_A_DQS_DP<17>
J 0
(610 4910);
DISPLAY 0.659574 (610 4910);
PAINT MONO (610 4910);
DISPLAY INVISIBLE (610 4910);
FORCEPROP 1 LASTPIN (600 4900) BN 17
J 2
(650 4910);
DISPLAY 0.617021 (650 4910);
PAINT PINK (650 4910);
FORCEPROP 2 LAST CDS_LIB mstr_standard
J 2
(650 4900);
DISPLAY 0.787234 (650 4900);
PAINT MONO (650 4900);
DISPLAY INVISIBLE (650 4900);
FORCEPROP 1 LAST BODY_TYPE PLUMBING
J 2
(650 4850);
DISPLAY 1.234043 (650 4850);
PAINT GREEN (650 4850);
DISPLAY INVISIBLE (650 4850);
FORCEPROP 1 LAST HDL_TAP TRUE
J 2
(325 4775);
DISPLAY 1.234043 (325 4775);
PAINT GREEN (325 4775);
DISPLAY INVISIBLE (325 4775);
FORCEPROP 1 LAST PATH I206
J 2
(650 4900);
DISPLAY 0.936170 (650 4900);
PAINT GREEN (650 4900);
DISPLAY INVISIBLE (650 4900);
FORCEADD TAP..6
R 2
(650 4800);
FORCEPROP 3 LASTPIN (600 4800) SIG_NAME M_A_DQS_DP<16>
J 0
(610 4810);
DISPLAY 0.659574 (610 4810);
PAINT MONO (610 4810);
DISPLAY INVISIBLE (610 4810);
FORCEPROP 1 LASTPIN (600 4800) BN 16
J 2
(650 4810);
DISPLAY 0.617021 (650 4810);
PAINT PINK (650 4810);
FORCEPROP 2 LAST CDS_LIB mstr_standard
J 0
(650 4800);
DISPLAY 0.787234 (650 4800);
PAINT MONO (650 4800);
DISPLAY INVISIBLE (650 4800);
FORCEPROP 1 LAST BODY_TYPE PLUMBING
J 2
(650 4750);
DISPLAY 1.234043 (650 4750);
PAINT GREEN (650 4750);
DISPLAY INVISIBLE (650 4750);
FORCEPROP 1 LAST HDL_TAP TRUE
J 2
(325 4675);
DISPLAY 1.234043 (325 4675);
PAINT GREEN (325 4675);
DISPLAY INVISIBLE (325 4675);
FORCEPROP 1 LAST PATH I207
J 2
(650 4800);
DISPLAY 0.936170 (650 4800);
PAINT GREEN (650 4800);
DISPLAY INVISIBLE (650 4800);
FORCEADD TAP..6
R 2
(650 4500);
FORCEPROP 3 LASTPIN (600 4500) SIG_NAME M_A_DQS_DP<13>
J 0
(610 4510);
DISPLAY 0.659574 (610 4510);
PAINT MONO (610 4510);
DISPLAY INVISIBLE (610 4510);
FORCEPROP 1 LASTPIN (600 4500) BN 13
J 2
(650 4510);
DISPLAY 0.617021 (650 4510);
PAINT PINK (650 4510);
FORCEPROP 2 LAST CDS_LIB mstr_standard
J 0
(650 4500);
DISPLAY 0.787234 (650 4500);
PAINT MONO (650 4500);
DISPLAY INVISIBLE (650 4500);
FORCEPROP 1 LAST BODY_TYPE PLUMBING
J 2
(650 4450);
DISPLAY 1.234043 (650 4450);
PAINT GREEN (650 4450);
DISPLAY INVISIBLE (650 4450);
FORCEPROP 1 LAST HDL_TAP TRUE
J 2
(325 4375);
DISPLAY 1.234043 (325 4375);
PAINT GREEN (325 4375);
DISPLAY INVISIBLE (325 4375);
FORCEPROP 1 LAST PATH I208
J 2
(650 4500);
DISPLAY 0.936170 (650 4500);
PAINT GREEN (650 4500);
DISPLAY INVISIBLE (650 4500);
FORCEADD TAP..6
R 2
(650 4600);
FORCEPROP 3 LASTPIN (600 4600) SIG_NAME M_A_DQS_DP<14>
J 0
(610 4610);
DISPLAY 0.659574 (610 4610);
PAINT MONO (610 4610);
DISPLAY INVISIBLE (610 4610);
FORCEPROP 1 LASTPIN (600 4600) BN 14
J 2
(650 4610);
DISPLAY 0.617021 (650 4610);
PAINT PINK (650 4610);
FORCEPROP 2 LAST CDS_LIB mstr_standard
J 0
(650 4600);
DISPLAY 0.787234 (650 4600);
PAINT MONO (650 4600);
DISPLAY INVISIBLE (650 4600);
FORCEPROP 1 LAST BODY_TYPE PLUMBING
J 2
(650 4550);
DISPLAY 1.234043 (650 4550);
PAINT GREEN (650 4550);
DISPLAY INVISIBLE (650 4550);
FORCEPROP 1 LAST HDL_TAP TRUE
J 2
(325 4475);
DISPLAY 1.234043 (325 4475);
PAINT GREEN (325 4475);
DISPLAY INVISIBLE (325 4475);
FORCEPROP 1 LAST PATH I209
J 2
(650 4600);
DISPLAY 0.936170 (650 4600);
PAINT GREEN (650 4600);
DISPLAY INVISIBLE (650 4600);
FORCEADD TAP..6
R 2
(650 4400);
FORCEPROP 3 LASTPIN (600 4400) SIG_NAME M_A_DQS_DP<12>
J 0
(610 4410);
DISPLAY 0.659574 (610 4410);
PAINT MONO (610 4410);
DISPLAY INVISIBLE (610 4410);
FORCEPROP 1 LASTPIN (600 4400) BN 12
J 2
(650 4410);
DISPLAY 0.617021 (650 4410);
PAINT PINK (650 4410);
FORCEPROP 2 LAST CDS_LIB mstr_standard
J 0
(650 4400);
DISPLAY 0.787234 (650 4400);
PAINT MONO (650 4400);
DISPLAY INVISIBLE (650 4400);
FORCEPROP 1 LAST BODY_TYPE PLUMBING
J 2
(650 4350);
DISPLAY 1.234043 (650 4350);
PAINT GREEN (650 4350);
DISPLAY INVISIBLE (650 4350);
FORCEPROP 1 LAST HDL_TAP TRUE
J 2
(325 4275);
DISPLAY 1.234043 (325 4275);
PAINT GREEN (325 4275);
DISPLAY INVISIBLE (325 4275);
FORCEPROP 1 LAST PATH I210
J 2
(650 4400);
DISPLAY 0.936170 (650 4400);
PAINT GREEN (650 4400);
DISPLAY INVISIBLE (650 4400);
FORCEADD OFFPAGE..3
(1550 4900);
FORCEPROP 2 LAST $XR0 23 
J 0
(1764 4900);
DISPLAY 0.638298 (1764 4900);
PAINT MONO (1764 4900);
FORCEPROP 2 LAST $XR1 44 
J 0
(1854 4900);
DISPLAY 0.638298 (1854 4900);
PAINT MONO (1854 4900);
FORCEPROP 2 LAST CDS_LIB mstr_standard
J 0
(1550 4900);
DISPLAY 0.787234 (1550 4900);
PAINT MONO (1550 4900);
DISPLAY INVISIBLE (1550 4900);
FORCEPROP 1 LAST OFFPAGE TRUE
J 0
(1875 4775);
DISPLAY 0.936170 (1875 4775);
PAINT GREEN (1875 4775);
DISPLAY INVISIBLE (1875 4775);
FORCEPROP 1 LAST COMMENT_BODY TRUE
J 0
(1500 4800);
DISPLAY 0.936170 (1500 4800);
PAINT GREEN (1500 4800);
DISPLAY INVISIBLE (1500 4800);
FORCEPROP 2 LAST PATH I211
J 0
(1750 4975);
DISPLAY 0.787234 (1750 4975);
PAINT MONO (1750 4975);
DISPLAY INVISIBLE (1750 4975);
FORCEADD TAP..6
R 2
(850 4850);
FORCEPROP 3 LASTPIN (800 4850) SIG_NAME M_A_DQS_DN<17>
J 0
(810 4860);
DISPLAY 0.659574 (810 4860);
PAINT MONO (810 4860);
DISPLAY INVISIBLE (810 4860);
FORCEPROP 1 LASTPIN (800 4850) BN 17
J 2
(850 4860);
DISPLAY 0.617021 (850 4860);
PAINT PINK (850 4860);
FORCEPROP 2 LAST CDS_LIB mstr_standard
J 2
(850 4850);
DISPLAY 0.787234 (850 4850);
PAINT MONO (850 4850);
DISPLAY INVISIBLE (850 4850);
FORCEPROP 1 LAST BODY_TYPE PLUMBING
J 2
(850 4800);
DISPLAY 1.234043 (850 4800);
PAINT GREEN (850 4800);
DISPLAY INVISIBLE (850 4800);
FORCEPROP 1 LAST HDL_TAP TRUE
J 2
(525 4725);
DISPLAY 1.234043 (525 4725);
PAINT GREEN (525 4725);
DISPLAY INVISIBLE (525 4725);
FORCEPROP 1 LAST PATH I212
J 2
(850 4850);
DISPLAY 0.936170 (850 4850);
PAINT GREEN (850 4850);
DISPLAY INVISIBLE (850 4850);
FORCEADD TAP..6
R 2
(850 4750);
FORCEPROP 3 LASTPIN (800 4750) SIG_NAME M_A_DQS_DN<16>
J 0
(810 4760);
DISPLAY 0.659574 (810 4760);
PAINT MONO (810 4760);
DISPLAY INVISIBLE (810 4760);
FORCEPROP 1 LASTPIN (800 4750) BN 16
J 2
(850 4760);
DISPLAY 0.617021 (850 4760);
PAINT PINK (850 4760);
FORCEPROP 2 LAST CDS_LIB mstr_standard
J 0
(850 4750);
DISPLAY 0.787234 (850 4750);
PAINT MONO (850 4750);
DISPLAY INVISIBLE (850 4750);
FORCEPROP 1 LAST BODY_TYPE PLUMBING
J 2
(850 4700);
DISPLAY 1.234043 (850 4700);
PAINT GREEN (850 4700);
DISPLAY INVISIBLE (850 4700);
FORCEPROP 1 LAST HDL_TAP TRUE
J 2
(525 4625);
DISPLAY 1.234043 (525 4625);
PAINT GREEN (525 4625);
DISPLAY INVISIBLE (525 4625);
FORCEPROP 1 LAST PATH I213
J 2
(850 4750);
DISPLAY 0.936170 (850 4750);
PAINT GREEN (850 4750);
DISPLAY INVISIBLE (850 4750);
FORCEADD TAP..6
R 2
(850 4650);
FORCEPROP 3 LASTPIN (800 4650) SIG_NAME M_A_DQS_DN<15>
J 0
(810 4660);
DISPLAY 0.659574 (810 4660);
PAINT MONO (810 4660);
DISPLAY INVISIBLE (810 4660);
FORCEPROP 1 LASTPIN (800 4650) BN 15
J 2
(850 4660);
DISPLAY 0.617021 (850 4660);
PAINT PINK (850 4660);
FORCEPROP 2 LAST CDS_LIB mstr_standard
J 0
(850 4650);
DISPLAY 0.787234 (850 4650);
PAINT MONO (850 4650);
DISPLAY INVISIBLE (850 4650);
FORCEPROP 1 LAST BODY_TYPE PLUMBING
J 2
(850 4600);
DISPLAY 1.234043 (850 4600);
PAINT GREEN (850 4600);
DISPLAY INVISIBLE (850 4600);
FORCEPROP 1 LAST HDL_TAP TRUE
J 2
(525 4525);
DISPLAY 1.234043 (525 4525);
PAINT GREEN (525 4525);
DISPLAY INVISIBLE (525 4525);
FORCEPROP 1 LAST PATH I214
J 2
(850 4650);
DISPLAY 0.936170 (850 4650);
PAINT GREEN (850 4650);
DISPLAY INVISIBLE (850 4650);
FORCEADD TAP..6
R 2
(850 4550);
FORCEPROP 3 LASTPIN (800 4550) SIG_NAME M_A_DQS_DN<14>
J 0
(810 4560);
DISPLAY 0.659574 (810 4560);
PAINT MONO (810 4560);
DISPLAY INVISIBLE (810 4560);
FORCEPROP 1 LASTPIN (800 4550) BN 14
J 2
(850 4560);
DISPLAY 0.617021 (850 4560);
PAINT PINK (850 4560);
FORCEPROP 2 LAST CDS_LIB mstr_standard
J 0
(850 4550);
DISPLAY 0.787234 (850 4550);
PAINT MONO (850 4550);
DISPLAY INVISIBLE (850 4550);
FORCEPROP 1 LAST BODY_TYPE PLUMBING
J 2
(850 4500);
DISPLAY 1.234043 (850 4500);
PAINT GREEN (850 4500);
DISPLAY INVISIBLE (850 4500);
FORCEPROP 1 LAST HDL_TAP TRUE
J 2
(525 4425);
DISPLAY 1.234043 (525 4425);
PAINT GREEN (525 4425);
DISPLAY INVISIBLE (525 4425);
FORCEPROP 1 LAST PATH I215
J 2
(850 4550);
DISPLAY 0.936170 (850 4550);
PAINT GREEN (850 4550);
DISPLAY INVISIBLE (850 4550);
FORCEADD TAP..6
R 2
(850 4450);
FORCEPROP 3 LASTPIN (800 4450) SIG_NAME M_A_DQS_DN<13>
J 0
(810 4460);
DISPLAY 0.659574 (810 4460);
PAINT MONO (810 4460);
DISPLAY INVISIBLE (810 4460);
FORCEPROP 1 LASTPIN (800 4450) BN 13
J 2
(850 4460);
DISPLAY 0.617021 (850 4460);
PAINT PINK (850 4460);
FORCEPROP 2 LAST CDS_LIB mstr_standard
J 0
(850 4450);
DISPLAY 0.787234 (850 4450);
PAINT MONO (850 4450);
DISPLAY INVISIBLE (850 4450);
FORCEPROP 1 LAST BODY_TYPE PLUMBING
J 2
(850 4400);
DISPLAY 1.234043 (850 4400);
PAINT GREEN (850 4400);
DISPLAY INVISIBLE (850 4400);
FORCEPROP 1 LAST HDL_TAP TRUE
J 2
(525 4325);
DISPLAY 1.234043 (525 4325);
PAINT GREEN (525 4325);
DISPLAY INVISIBLE (525 4325);
FORCEPROP 1 LAST PATH I216
J 2
(850 4450);
DISPLAY 0.936170 (850 4450);
PAINT GREEN (850 4450);
DISPLAY INVISIBLE (850 4450);
FORCEADD TAP..6
R 2
(850 4350);
FORCEPROP 3 LASTPIN (800 4350) SIG_NAME M_A_DQS_DN<12>
J 0
(810 4360);
DISPLAY 0.659574 (810 4360);
PAINT MONO (810 4360);
DISPLAY INVISIBLE (810 4360);
FORCEPROP 1 LASTPIN (800 4350) BN 12
J 2
(850 4360);
DISPLAY 0.617021 (850 4360);
PAINT PINK (850 4360);
FORCEPROP 2 LAST CDS_LIB mstr_standard
J 0
(850 4350);
DISPLAY 0.787234 (850 4350);
PAINT MONO (850 4350);
DISPLAY INVISIBLE (850 4350);
FORCEPROP 1 LAST BODY_TYPE PLUMBING
J 2
(850 4300);
DISPLAY 1.234043 (850 4300);
PAINT GREEN (850 4300);
DISPLAY INVISIBLE (850 4300);
FORCEPROP 1 LAST HDL_TAP TRUE
J 2
(525 4225);
DISPLAY 1.234043 (525 4225);
PAINT GREEN (525 4225);
DISPLAY INVISIBLE (525 4225);
FORCEPROP 1 LAST PATH I217
J 2
(850 4350);
DISPLAY 0.936170 (850 4350);
PAINT GREEN (850 4350);
DISPLAY INVISIBLE (850 4350);
FORCEADD TAP..6
R 2
(850 4250);
FORCEPROP 3 LASTPIN (800 4250) SIG_NAME M_A_DQS_DN<11>
J 0
(810 4260);
DISPLAY 0.659574 (810 4260);
PAINT MONO (810 4260);
DISPLAY INVISIBLE (810 4260);
FORCEPROP 1 LASTPIN (800 4250) BN 11
J 2
(850 4260);
DISPLAY 0.617021 (850 4260);
PAINT PINK (850 4260);
FORCEPROP 2 LAST CDS_LIB mstr_standard
J 0
(850 4250);
DISPLAY 0.787234 (850 4250);
PAINT MONO (850 4250);
DISPLAY INVISIBLE (850 4250);
FORCEPROP 1 LAST BODY_TYPE PLUMBING
J 2
(850 4200);
DISPLAY 1.234043 (850 4200);
PAINT GREEN (850 4200);
DISPLAY INVISIBLE (850 4200);
FORCEPROP 1 LAST HDL_TAP TRUE
J 2
(525 4125);
DISPLAY 1.234043 (525 4125);
PAINT GREEN (525 4125);
DISPLAY INVISIBLE (525 4125);
FORCEPROP 1 LAST PATH I218
J 2
(850 4250);
DISPLAY 0.936170 (850 4250);
PAINT GREEN (850 4250);
DISPLAY INVISIBLE (850 4250);
FORCEADD TAP..6
R 2
(850 4150);
FORCEPROP 3 LASTPIN (800 4150) SIG_NAME M_A_DQS_DN<10>
J 0
(810 4160);
DISPLAY 0.659574 (810 4160);
PAINT MONO (810 4160);
DISPLAY INVISIBLE (810 4160);
FORCEPROP 1 LASTPIN (800 4150) BN 10
J 2
(850 4160);
DISPLAY 0.617021 (850 4160);
PAINT PINK (850 4160);
FORCEPROP 2 LAST CDS_LIB mstr_standard
J 0
(850 4150);
DISPLAY 0.787234 (850 4150);
PAINT MONO (850 4150);
DISPLAY INVISIBLE (850 4150);
FORCEPROP 1 LAST BODY_TYPE PLUMBING
J 2
(850 4100);
DISPLAY 1.234043 (850 4100);
PAINT GREEN (850 4100);
DISPLAY INVISIBLE (850 4100);
FORCEPROP 1 LAST HDL_TAP TRUE
J 2
(525 4025);
DISPLAY 1.234043 (525 4025);
PAINT GREEN (525 4025);
DISPLAY INVISIBLE (525 4025);
FORCEPROP 1 LAST PATH I219
J 2
(850 4150);
DISPLAY 0.936170 (850 4150);
PAINT GREEN (850 4150);
DISPLAY INVISIBLE (850 4150);
FORCEADD TAP..6
(-3150 4400);
FORCEPROP 3 LASTPIN (-3100 4400) SIG_NAME M_A_MA<17>
J 0
(-3090 4410);
DISPLAY 0.659574 (-3090 4410);
PAINT MONO (-3090 4410);
DISPLAY INVISIBLE (-3090 4410);
FORCEPROP 1 LASTPIN (-3100 4400) BN 17
J 0
(-3150 4410);
DISPLAY 0.617021 (-3150 4410);
PAINT PINK (-3150 4410);
FORCEPROP 2 LAST CDS_LIB mstr_standard
J 0
(-3150 4400);
DISPLAY 0.787234 (-3150 4400);
PAINT MONO (-3150 4400);
DISPLAY INVISIBLE (-3150 4400);
FORCEPROP 1 LAST BODY_TYPE PLUMBING
J 0
(-3150 4350);
DISPLAY 1.234043 (-3150 4350);
PAINT GREEN (-3150 4350);
DISPLAY INVISIBLE (-3150 4350);
FORCEPROP 1 LAST HDL_TAP TRUE
J 0
(-2825 4275);
DISPLAY 1.234043 (-2825 4275);
PAINT GREEN (-2825 4275);
DISPLAY INVISIBLE (-2825 4275);
FORCEPROP 1 LAST PATH I22
J 0
(-3150 4400);
DISPLAY 0.936170 (-3150 4400);
PAINT GREEN (-3150 4400);
DISPLAY INVISIBLE (-3150 4400);
FORCEADD TAP..6
R 2
(850 4050);
FORCEPROP 3 LASTPIN (800 4050) SIG_NAME M_A_DQS_DN<9>
J 0
(810 4060);
DISPLAY 0.659574 (810 4060);
PAINT MONO (810 4060);
DISPLAY INVISIBLE (810 4060);
FORCEPROP 1 LASTPIN (800 4050) BN 9
J 2
(850 4060);
DISPLAY 0.617021 (850 4060);
PAINT PINK (850 4060);
FORCEPROP 2 LAST CDS_LIB mstr_standard
J 0
(850 4050);
DISPLAY 0.787234 (850 4050);
PAINT MONO (850 4050);
DISPLAY INVISIBLE (850 4050);
FORCEPROP 1 LAST BODY_TYPE PLUMBING
J 2
(850 4000);
DISPLAY 1.234043 (850 4000);
PAINT GREEN (850 4000);
DISPLAY INVISIBLE (850 4000);
FORCEPROP 1 LAST HDL_TAP TRUE
J 2
(525 3925);
DISPLAY 1.234043 (525 3925);
PAINT GREEN (525 3925);
DISPLAY INVISIBLE (525 3925);
FORCEPROP 1 LAST PATH I220
J 2
(850 4050);
DISPLAY 0.936170 (850 4050);
PAINT GREEN (850 4050);
DISPLAY INVISIBLE (850 4050);
FORCEADD TAP..6
R 2
(850 3950);
FORCEPROP 3 LASTPIN (800 3950) SIG_NAME M_A_DQS_DN<8>
J 0
(810 3960);
DISPLAY 0.659574 (810 3960);
PAINT MONO (810 3960);
DISPLAY INVISIBLE (810 3960);
FORCEPROP 1 LASTPIN (800 3950) BN 8
J 2
(850 3960);
DISPLAY 0.617021 (850 3960);
PAINT PINK (850 3960);
FORCEPROP 2 LAST CDS_LIB mstr_standard
J 0
(850 3950);
DISPLAY 0.787234 (850 3950);
PAINT MONO (850 3950);
DISPLAY INVISIBLE (850 3950);
FORCEPROP 1 LAST BODY_TYPE PLUMBING
J 2
(850 3900);
DISPLAY 1.234043 (850 3900);
PAINT GREEN (850 3900);
DISPLAY INVISIBLE (850 3900);
FORCEPROP 1 LAST HDL_TAP TRUE
J 2
(525 3825);
DISPLAY 1.234043 (525 3825);
PAINT GREEN (525 3825);
DISPLAY INVISIBLE (525 3825);
FORCEPROP 1 LAST PATH I221
J 2
(850 3950);
DISPLAY 0.936170 (850 3950);
PAINT GREEN (850 3950);
DISPLAY INVISIBLE (850 3950);
FORCEADD TAP..6
R 2
(850 3850);
FORCEPROP 3 LASTPIN (800 3850) SIG_NAME M_A_DQS_DN<7>
J 0
(810 3860);
DISPLAY 0.659574 (810 3860);
PAINT MONO (810 3860);
DISPLAY INVISIBLE (810 3860);
FORCEPROP 1 LASTPIN (800 3850) BN 7
J 2
(850 3860);
DISPLAY 0.617021 (850 3860);
PAINT PINK (850 3860);
FORCEPROP 2 LAST CDS_LIB mstr_standard
J 0
(850 3850);
DISPLAY 0.787234 (850 3850);
PAINT MONO (850 3850);
DISPLAY INVISIBLE (850 3850);
FORCEPROP 1 LAST BODY_TYPE PLUMBING
J 2
(850 3800);
DISPLAY 1.234043 (850 3800);
PAINT GREEN (850 3800);
DISPLAY INVISIBLE (850 3800);
FORCEPROP 1 LAST HDL_TAP TRUE
J 2
(525 3725);
DISPLAY 1.234043 (525 3725);
PAINT GREEN (525 3725);
DISPLAY INVISIBLE (525 3725);
FORCEPROP 1 LAST PATH I222
J 2
(850 3850);
DISPLAY 0.936170 (850 3850);
PAINT GREEN (850 3850);
DISPLAY INVISIBLE (850 3850);
FORCEADD TAP..6
R 2
(850 3750);
FORCEPROP 3 LASTPIN (800 3750) SIG_NAME M_A_DQS_DN<6>
J 0
(810 3760);
DISPLAY 0.659574 (810 3760);
PAINT MONO (810 3760);
DISPLAY INVISIBLE (810 3760);
FORCEPROP 1 LASTPIN (800 3750) BN 6
J 2
(850 3760);
DISPLAY 0.617021 (850 3760);
PAINT PINK (850 3760);
FORCEPROP 2 LAST CDS_LIB mstr_standard
J 0
(850 3750);
DISPLAY 0.787234 (850 3750);
PAINT MONO (850 3750);
DISPLAY INVISIBLE (850 3750);
FORCEPROP 1 LAST BODY_TYPE PLUMBING
J 2
(850 3700);
DISPLAY 1.234043 (850 3700);
PAINT GREEN (850 3700);
DISPLAY INVISIBLE (850 3700);
FORCEPROP 1 LAST HDL_TAP TRUE
J 2
(525 3625);
DISPLAY 1.234043 (525 3625);
PAINT GREEN (525 3625);
DISPLAY INVISIBLE (525 3625);
FORCEPROP 1 LAST PATH I223
J 2
(850 3750);
DISPLAY 0.936170 (850 3750);
PAINT GREEN (850 3750);
DISPLAY INVISIBLE (850 3750);
FORCEADD TAP..6
R 2
(850 3650);
FORCEPROP 3 LASTPIN (800 3650) SIG_NAME M_A_DQS_DN<5>
J 0
(810 3660);
DISPLAY 0.659574 (810 3660);
PAINT MONO (810 3660);
DISPLAY INVISIBLE (810 3660);
FORCEPROP 1 LASTPIN (800 3650) BN 5
J 2
(850 3660);
DISPLAY 0.617021 (850 3660);
PAINT PINK (850 3660);
FORCEPROP 2 LAST CDS_LIB mstr_standard
J 0
(850 3650);
DISPLAY 0.787234 (850 3650);
PAINT MONO (850 3650);
DISPLAY INVISIBLE (850 3650);
FORCEPROP 1 LAST BODY_TYPE PLUMBING
J 2
(850 3600);
DISPLAY 1.234043 (850 3600);
PAINT GREEN (850 3600);
DISPLAY INVISIBLE (850 3600);
FORCEPROP 1 LAST HDL_TAP TRUE
J 2
(525 3525);
DISPLAY 1.234043 (525 3525);
PAINT GREEN (525 3525);
DISPLAY INVISIBLE (525 3525);
FORCEPROP 1 LAST PATH I224
J 2
(850 3650);
DISPLAY 0.936170 (850 3650);
PAINT GREEN (850 3650);
DISPLAY INVISIBLE (850 3650);
FORCEADD TAP..6
R 2
(850 3550);
FORCEPROP 3 LASTPIN (800 3550) SIG_NAME M_A_DQS_DN<4>
J 0
(810 3560);
DISPLAY 0.659574 (810 3560);
PAINT MONO (810 3560);
DISPLAY INVISIBLE (810 3560);
FORCEPROP 1 LASTPIN (800 3550) BN 4
J 2
(850 3560);
DISPLAY 0.617021 (850 3560);
PAINT PINK (850 3560);
FORCEPROP 2 LAST CDS_LIB mstr_standard
J 0
(850 3550);
DISPLAY 0.787234 (850 3550);
PAINT MONO (850 3550);
DISPLAY INVISIBLE (850 3550);
FORCEPROP 1 LAST BODY_TYPE PLUMBING
J 2
(850 3500);
DISPLAY 1.234043 (850 3500);
PAINT GREEN (850 3500);
DISPLAY INVISIBLE (850 3500);
FORCEPROP 1 LAST HDL_TAP TRUE
J 2
(525 3425);
DISPLAY 1.234043 (525 3425);
PAINT GREEN (525 3425);
DISPLAY INVISIBLE (525 3425);
FORCEPROP 1 LAST PATH I225
J 2
(850 3550);
DISPLAY 0.936170 (850 3550);
PAINT GREEN (850 3550);
DISPLAY INVISIBLE (850 3550);
FORCEADD TAP..6
R 2
(850 3450);
FORCEPROP 3 LASTPIN (800 3450) SIG_NAME M_A_DQS_DN<3>
J 0
(810 3460);
DISPLAY 0.659574 (810 3460);
PAINT MONO (810 3460);
DISPLAY INVISIBLE (810 3460);
FORCEPROP 1 LASTPIN (800 3450) BN 3
J 2
(850 3460);
DISPLAY 0.617021 (850 3460);
PAINT PINK (850 3460);
FORCEPROP 2 LAST CDS_LIB mstr_standard
J 0
(850 3450);
DISPLAY 0.787234 (850 3450);
PAINT MONO (850 3450);
DISPLAY INVISIBLE (850 3450);
FORCEPROP 1 LAST BODY_TYPE PLUMBING
J 2
(850 3400);
DISPLAY 1.234043 (850 3400);
PAINT GREEN (850 3400);
DISPLAY INVISIBLE (850 3400);
FORCEPROP 1 LAST HDL_TAP TRUE
J 2
(525 3325);
DISPLAY 1.234043 (525 3325);
PAINT GREEN (525 3325);
DISPLAY INVISIBLE (525 3325);
FORCEPROP 1 LAST PATH I226
J 2
(850 3450);
DISPLAY 0.936170 (850 3450);
PAINT GREEN (850 3450);
DISPLAY INVISIBLE (850 3450);
FORCEADD TAP..6
R 2
(850 3350);
FORCEPROP 3 LASTPIN (800 3350) SIG_NAME M_A_DQS_DN<2>
J 0
(810 3360);
DISPLAY 0.659574 (810 3360);
PAINT MONO (810 3360);
DISPLAY INVISIBLE (810 3360);
FORCEPROP 1 LASTPIN (800 3350) BN 2
J 2
(850 3360);
DISPLAY 0.617021 (850 3360);
PAINT PINK (850 3360);
FORCEPROP 2 LAST CDS_LIB mstr_standard
J 0
(850 3350);
DISPLAY 0.787234 (850 3350);
PAINT MONO (850 3350);
DISPLAY INVISIBLE (850 3350);
FORCEPROP 1 LAST BODY_TYPE PLUMBING
J 2
(850 3300);
DISPLAY 1.234043 (850 3300);
PAINT GREEN (850 3300);
DISPLAY INVISIBLE (850 3300);
FORCEPROP 1 LAST HDL_TAP TRUE
J 2
(525 3225);
DISPLAY 1.234043 (525 3225);
PAINT GREEN (525 3225);
DISPLAY INVISIBLE (525 3225);
FORCEPROP 1 LAST PATH I227
J 2
(850 3350);
DISPLAY 0.936170 (850 3350);
PAINT GREEN (850 3350);
DISPLAY INVISIBLE (850 3350);
FORCEADD TAP..6
R 2
(850 3250);
FORCEPROP 3 LASTPIN (800 3250) SIG_NAME M_A_DQS_DN<1>
J 0
(810 3260);
DISPLAY 0.659574 (810 3260);
PAINT MONO (810 3260);
DISPLAY INVISIBLE (810 3260);
FORCEPROP 1 LASTPIN (800 3250) BN 1
J 2
(850 3260);
DISPLAY 0.617021 (850 3260);
PAINT PINK (850 3260);
FORCEPROP 2 LAST CDS_LIB mstr_standard
J 0
(850 3250);
DISPLAY 0.787234 (850 3250);
PAINT MONO (850 3250);
DISPLAY INVISIBLE (850 3250);
FORCEPROP 1 LAST BODY_TYPE PLUMBING
J 2
(850 3200);
DISPLAY 1.234043 (850 3200);
PAINT GREEN (850 3200);
DISPLAY INVISIBLE (850 3200);
FORCEPROP 1 LAST HDL_TAP TRUE
J 2
(525 3125);
DISPLAY 1.234043 (525 3125);
PAINT GREEN (525 3125);
DISPLAY INVISIBLE (525 3125);
FORCEPROP 1 LAST PATH I228
J 2
(850 3250);
DISPLAY 0.936170 (850 3250);
PAINT GREEN (850 3250);
DISPLAY INVISIBLE (850 3250);
FORCEADD TAP..6
R 2
(850 3150);
FORCEPROP 3 LASTPIN (800 3150) SIG_NAME M_A_DQS_DN<0>
J 0
(810 3160);
DISPLAY 0.659574 (810 3160);
PAINT MONO (810 3160);
DISPLAY INVISIBLE (810 3160);
FORCEPROP 1 LASTPIN (800 3150) BN 0
J 2
(850 3160);
DISPLAY 0.617021 (850 3160);
PAINT PINK (850 3160);
FORCEPROP 2 LAST CDS_LIB mstr_standard
J 0
(850 3150);
DISPLAY 0.787234 (850 3150);
PAINT MONO (850 3150);
DISPLAY INVISIBLE (850 3150);
FORCEPROP 1 LAST BODY_TYPE PLUMBING
J 2
(850 3100);
DISPLAY 1.234043 (850 3100);
PAINT GREEN (850 3100);
DISPLAY INVISIBLE (850 3100);
FORCEPROP 1 LAST HDL_TAP TRUE
J 2
(525 3025);
DISPLAY 1.234043 (525 3025);
PAINT GREEN (525 3025);
DISPLAY INVISIBLE (525 3025);
FORCEPROP 1 LAST PATH I229
J 2
(850 3150);
DISPLAY 0.936170 (850 3150);
PAINT GREEN (850 3150);
DISPLAY INVISIBLE (850 3150);
FORCEADD TAP..6
(-3150 4350);
FORCEPROP 3 LASTPIN (-3100 4350) SIG_NAME M_A_MA<16>
J 0
(-3090 4360);
DISPLAY 0.659574 (-3090 4360);
PAINT MONO (-3090 4360);
DISPLAY INVISIBLE (-3090 4360);
FORCEPROP 1 LASTPIN (-3100 4350) BN 16
J 0
(-3150 4360);
DISPLAY 0.617021 (-3150 4360);
PAINT PINK (-3150 4360);
FORCEPROP 2 LAST CDS_LIB mstr_standard
J 2
(-3150 4350);
DISPLAY 0.787234 (-3150 4350);
PAINT MONO (-3150 4350);
DISPLAY INVISIBLE (-3150 4350);
FORCEPROP 1 LAST BODY_TYPE PLUMBING
J 0
(-3150 4300);
DISPLAY 1.234043 (-3150 4300);
PAINT GREEN (-3150 4300);
DISPLAY INVISIBLE (-3150 4300);
FORCEPROP 1 LAST HDL_TAP TRUE
J 0
(-2825 4225);
DISPLAY 1.234043 (-2825 4225);
PAINT GREEN (-2825 4225);
DISPLAY INVISIBLE (-2825 4225);
FORCEPROP 1 LAST PATH I23
J 0
(-3150 4350);
DISPLAY 0.936170 (-3150 4350);
PAINT GREEN (-3150 4350);
DISPLAY INVISIBLE (-3150 4350);
FORCEADD TAP..6
(-3150 2450);
FORCEPROP 3 LASTPIN (-3100 2450) SIG_NAME M_A_ODT<0>
J 0
(-3090 2460);
DISPLAY 0.659574 (-3090 2460);
PAINT MONO (-3090 2460);
DISPLAY INVISIBLE (-3090 2460);
FORCEPROP 1 LASTPIN (-3100 2450) BN 0
J 0
(-3150 2460);
DISPLAY 0.617021 (-3150 2460);
PAINT PINK (-3150 2460);
FORCEPROP 2 LAST CDS_LIB mstr_standard
J 0
(-3150 2450);
DISPLAY 0.787234 (-3150 2450);
PAINT MONO (-3150 2450);
DISPLAY INVISIBLE (-3150 2450);
FORCEPROP 1 LAST BODY_TYPE PLUMBING
J 0
(-3150 2400);
DISPLAY 1.234043 (-3150 2400);
PAINT GREEN (-3150 2400);
DISPLAY INVISIBLE (-3150 2400);
FORCEPROP 1 LAST HDL_TAP TRUE
J 0
(-2825 2325);
DISPLAY 1.234043 (-2825 2325);
PAINT GREEN (-2825 2325);
DISPLAY INVISIBLE (-2825 2325);
FORCEPROP 1 LAST PATH I235
J 0
(-3150 2450);
DISPLAY 0.936170 (-3150 2450);
PAINT GREEN (-3150 2450);
DISPLAY INVISIBLE (-3150 2450);
FORCEADD TAP..6
(-3150 2500);
FORCEPROP 3 LASTPIN (-3100 2500) SIG_NAME M_A_ODT<1>
J 0
(-3090 2510);
DISPLAY 0.659574 (-3090 2510);
PAINT MONO (-3090 2510);
DISPLAY INVISIBLE (-3090 2510);
FORCEPROP 1 LASTPIN (-3100 2500) BN 1
J 0
(-3150 2510);
DISPLAY 0.617021 (-3150 2510);
PAINT PINK (-3150 2510);
FORCEPROP 2 LAST CDS_LIB mstr_standard
J 0
(-3150 2500);
DISPLAY 0.787234 (-3150 2500);
PAINT MONO (-3150 2500);
DISPLAY INVISIBLE (-3150 2500);
FORCEPROP 1 LAST BODY_TYPE PLUMBING
J 0
(-3150 2450);
DISPLAY 1.234043 (-3150 2450);
PAINT GREEN (-3150 2450);
DISPLAY INVISIBLE (-3150 2450);
FORCEPROP 1 LAST HDL_TAP TRUE
J 0
(-2825 2375);
DISPLAY 1.234043 (-2825 2375);
PAINT GREEN (-2825 2375);
DISPLAY INVISIBLE (-2825 2375);
FORCEPROP 1 LAST PATH I236
J 0
(-3150 2500);
DISPLAY 0.936170 (-3150 2500);
PAINT GREEN (-3150 2500);
DISPLAY INVISIBLE (-3150 2500);
FORCEADD OFFPAGE..1
(-3800 2550);
FORCEPROP 2 LAST $XR0 23 
J 0
(-4021 2550);
DISPLAY 0.638298 (-4021 2550);
PAINT MONO (-4021 2550);
FORCEPROP 2 LAST $XR1 44 
J 0
(-4111 2550);
DISPLAY 0.638298 (-4111 2550);
PAINT MONO (-4111 2550);
FORCEPROP 2 LAST CDS_LIB mstr_standard
J 0
(-3800 2550);
DISPLAY 0.787234 (-3800 2550);
PAINT MONO (-3800 2550);
DISPLAY INVISIBLE (-3800 2550);
FORCEPROP 1 LAST OFFPAGE TRUE
J 0
(-3475 2425);
DISPLAY 0.936170 (-3475 2425);
PAINT GREEN (-3475 2425);
DISPLAY INVISIBLE (-3475 2425);
FORCEPROP 1 LAST COMMENT_BODY TRUE
J 0
(-3675 2450);
DISPLAY 0.936170 (-3675 2450);
PAINT GREEN (-3675 2450);
DISPLAY INVISIBLE (-3675 2450);
FORCEPROP 2 LAST PATH I237
J 0
(-3750 2625);
DISPLAY 0.787234 (-3750 2625);
PAINT MONO (-3750 2625);
DISPLAY INVISIBLE (-3750 2625);
FORCEADD TAP..6
(-3150 2650);
FORCEPROP 3 LASTPIN (-3100 2650) SIG_NAME M_A_CKE<1>
J 0
(-3090 2660);
DISPLAY 0.659574 (-3090 2660);
PAINT MONO (-3090 2660);
DISPLAY INVISIBLE (-3090 2660);
FORCEPROP 1 LASTPIN (-3100 2650) BN 1
J 0
(-3150 2660);
DISPLAY 0.617021 (-3150 2660);
PAINT PINK (-3150 2660);
FORCEPROP 2 LAST CDS_LIB mstr_standard
J 0
(-3150 2650);
DISPLAY 0.787234 (-3150 2650);
PAINT MONO (-3150 2650);
DISPLAY INVISIBLE (-3150 2650);
FORCEPROP 1 LAST BODY_TYPE PLUMBING
J 0
(-3150 2600);
DISPLAY 1.234043 (-3150 2600);
PAINT GREEN (-3150 2600);
DISPLAY INVISIBLE (-3150 2600);
FORCEPROP 1 LAST HDL_TAP TRUE
J 0
(-2825 2525);
DISPLAY 1.234043 (-2825 2525);
PAINT GREEN (-2825 2525);
DISPLAY INVISIBLE (-2825 2525);
FORCEPROP 1 LAST PATH I238
J 0
(-3150 2650);
DISPLAY 0.936170 (-3150 2650);
PAINT GREEN (-3150 2650);
DISPLAY INVISIBLE (-3150 2650);
FORCEADD TAP..6
(-3150 2600);
FORCEPROP 3 LASTPIN (-3100 2600) SIG_NAME M_A_CKE<0>
J 0
(-3090 2610);
DISPLAY 0.659574 (-3090 2610);
PAINT MONO (-3090 2610);
DISPLAY INVISIBLE (-3090 2610);
FORCEPROP 1 LASTPIN (-3100 2600) BN 0
J 0
(-3150 2610);
DISPLAY 0.617021 (-3150 2610);
PAINT PINK (-3150 2610);
FORCEPROP 2 LAST CDS_LIB mstr_standard
J 0
(-3150 2600);
DISPLAY 0.787234 (-3150 2600);
PAINT MONO (-3150 2600);
DISPLAY INVISIBLE (-3150 2600);
FORCEPROP 1 LAST BODY_TYPE PLUMBING
J 0
(-3150 2550);
DISPLAY 1.234043 (-3150 2550);
PAINT GREEN (-3150 2550);
DISPLAY INVISIBLE (-3150 2550);
FORCEPROP 1 LAST HDL_TAP TRUE
J 0
(-2825 2475);
DISPLAY 1.234043 (-2825 2475);
PAINT GREEN (-2825 2475);
DISPLAY INVISIBLE (-2825 2475);
FORCEPROP 1 LAST PATH I239
J 0
(-3150 2600);
DISPLAY 0.936170 (-3150 2600);
PAINT GREEN (-3150 2600);
DISPLAY INVISIBLE (-3150 2600);
FORCEADD TAP..6
(-3150 4300);
FORCEPROP 3 LASTPIN (-3100 4300) SIG_NAME M_A_MA<15>
J 0
(-3090 4310);
DISPLAY 0.659574 (-3090 4310);
PAINT MONO (-3090 4310);
DISPLAY INVISIBLE (-3090 4310);
FORCEPROP 1 LASTPIN (-3100 4300) BN 15
J 0
(-3150 4310);
DISPLAY 0.617021 (-3150 4310);
PAINT PINK (-3150 4310);
FORCEPROP 2 LAST CDS_LIB mstr_standard
J 2
(-3150 4300);
DISPLAY 0.787234 (-3150 4300);
PAINT MONO (-3150 4300);
DISPLAY INVISIBLE (-3150 4300);
FORCEPROP 1 LAST BODY_TYPE PLUMBING
J 0
(-3150 4250);
DISPLAY 1.234043 (-3150 4250);
PAINT GREEN (-3150 4250);
DISPLAY INVISIBLE (-3150 4250);
FORCEPROP 1 LAST HDL_TAP TRUE
J 0
(-2825 4175);
DISPLAY 1.234043 (-2825 4175);
PAINT GREEN (-2825 4175);
DISPLAY INVISIBLE (-2825 4175);
FORCEPROP 1 LAST PATH I24
J 0
(-3150 4300);
DISPLAY 0.936170 (-3150 4300);
PAINT GREEN (-3150 4300);
DISPLAY INVISIBLE (-3150 4300);
FORCEADD OFFPAGE..1
(-3800 2700);
FORCEPROP 2 LAST $XR0 23 
J 0
(-4021 2700);
DISPLAY 0.638298 (-4021 2700);
PAINT MONO (-4021 2700);
FORCEPROP 2 LAST $XR1 44 
J 0
(-4111 2700);
DISPLAY 0.638298 (-4111 2700);
PAINT MONO (-4111 2700);
FORCEPROP 2 LAST CDS_LIB mstr_standard
J 0
(-3800 2700);
DISPLAY 0.787234 (-3800 2700);
PAINT MONO (-3800 2700);
DISPLAY INVISIBLE (-3800 2700);
FORCEPROP 1 LAST OFFPAGE TRUE
J 0
(-3475 2575);
DISPLAY 0.936170 (-3475 2575);
PAINT GREEN (-3475 2575);
DISPLAY INVISIBLE (-3475 2575);
FORCEPROP 1 LAST COMMENT_BODY TRUE
J 0
(-3675 2600);
DISPLAY 0.936170 (-3675 2600);
PAINT GREEN (-3675 2600);
DISPLAY INVISIBLE (-3675 2600);
FORCEPROP 2 LAST PATH I240
J 0
(-3750 2775);
DISPLAY 0.787234 (-3750 2775);
PAINT MONO (-3750 2775);
DISPLAY INVISIBLE (-3750 2775);
FORCEADD TAP..6
(-3150 2900);
FORCEPROP 3 LASTPIN (-3100 2900) SIG_NAME M_A_CS_N<3>
J 0
(-3090 2910);
DISPLAY 0.659574 (-3090 2910);
PAINT MONO (-3090 2910);
DISPLAY INVISIBLE (-3090 2910);
FORCEPROP 1 LASTPIN (-3100 2900) BN 3
J 0
(-3150 2910);
DISPLAY 0.617021 (-3150 2910);
PAINT PINK (-3150 2910);
FORCEPROP 2 LAST CDS_LIB mstr_standard
J 0
(-3150 2900);
DISPLAY 0.787234 (-3150 2900);
PAINT MONO (-3150 2900);
DISPLAY INVISIBLE (-3150 2900);
FORCEPROP 1 LAST BODY_TYPE PLUMBING
J 0
(-3150 2850);
DISPLAY 1.234043 (-3150 2850);
PAINT GREEN (-3150 2850);
DISPLAY INVISIBLE (-3150 2850);
FORCEPROP 1 LAST HDL_TAP TRUE
J 0
(-2825 2775);
DISPLAY 1.234043 (-2825 2775);
PAINT GREEN (-2825 2775);
DISPLAY INVISIBLE (-2825 2775);
FORCEPROP 1 LAST PATH I241
J 0
(-3150 2900);
DISPLAY 0.936170 (-3150 2900);
PAINT GREEN (-3150 2900);
DISPLAY INVISIBLE (-3150 2900);
FORCEADD TAP..6
(-3150 2850);
FORCEPROP 3 LASTPIN (-3100 2850) SIG_NAME M_A_CS_N<2>
J 0
(-3090 2860);
DISPLAY 0.659574 (-3090 2860);
PAINT MONO (-3090 2860);
DISPLAY INVISIBLE (-3090 2860);
FORCEPROP 1 LASTPIN (-3100 2850) BN 2
J 0
(-3150 2860);
DISPLAY 0.617021 (-3150 2860);
PAINT PINK (-3150 2860);
FORCEPROP 2 LAST CDS_LIB mstr_standard
J 0
(-3150 2850);
DISPLAY 0.787234 (-3150 2850);
PAINT MONO (-3150 2850);
DISPLAY INVISIBLE (-3150 2850);
FORCEPROP 1 LAST BODY_TYPE PLUMBING
J 0
(-3150 2800);
DISPLAY 1.234043 (-3150 2800);
PAINT GREEN (-3150 2800);
DISPLAY INVISIBLE (-3150 2800);
FORCEPROP 1 LAST HDL_TAP TRUE
J 0
(-2825 2725);
DISPLAY 1.234043 (-2825 2725);
PAINT GREEN (-2825 2725);
DISPLAY INVISIBLE (-2825 2725);
FORCEPROP 1 LAST PATH I242
J 0
(-3150 2850);
DISPLAY 0.936170 (-3150 2850);
PAINT GREEN (-3150 2850);
DISPLAY INVISIBLE (-3150 2850);
FORCEADD TAP..6
(-3150 2800);
FORCEPROP 3 LASTPIN (-3100 2800) SIG_NAME M_A_CS_N<1>
J 0
(-3090 2810);
DISPLAY 0.659574 (-3090 2810);
PAINT MONO (-3090 2810);
DISPLAY INVISIBLE (-3090 2810);
FORCEPROP 1 LASTPIN (-3100 2800) BN 1
J 0
(-3150 2810);
DISPLAY 0.617021 (-3150 2810);
PAINT PINK (-3150 2810);
FORCEPROP 2 LAST CDS_LIB mstr_standard
J 0
(-3150 2800);
DISPLAY 0.787234 (-3150 2800);
PAINT MONO (-3150 2800);
DISPLAY INVISIBLE (-3150 2800);
FORCEPROP 1 LAST BODY_TYPE PLUMBING
J 0
(-3150 2750);
DISPLAY 1.234043 (-3150 2750);
PAINT GREEN (-3150 2750);
DISPLAY INVISIBLE (-3150 2750);
FORCEPROP 1 LAST HDL_TAP TRUE
J 0
(-2825 2675);
DISPLAY 1.234043 (-2825 2675);
PAINT GREEN (-2825 2675);
DISPLAY INVISIBLE (-2825 2675);
FORCEPROP 1 LAST PATH I243
J 0
(-3150 2800);
DISPLAY 0.936170 (-3150 2800);
PAINT GREEN (-3150 2800);
DISPLAY INVISIBLE (-3150 2800);
FORCEADD TAP..6
(-3150 2750);
FORCEPROP 3 LASTPIN (-3100 2750) SIG_NAME M_A_CS_N<0>
J 0
(-3090 2760);
DISPLAY 0.659574 (-3090 2760);
PAINT MONO (-3090 2760);
DISPLAY INVISIBLE (-3090 2760);
FORCEPROP 1 LASTPIN (-3100 2750) BN 0
J 0
(-3150 2760);
DISPLAY 0.617021 (-3150 2760);
PAINT PINK (-3150 2760);
FORCEPROP 2 LAST CDS_LIB mstr_standard
J 0
(-3150 2750);
DISPLAY 0.787234 (-3150 2750);
PAINT MONO (-3150 2750);
DISPLAY INVISIBLE (-3150 2750);
FORCEPROP 1 LAST BODY_TYPE PLUMBING
J 0
(-3150 2700);
DISPLAY 1.234043 (-3150 2700);
PAINT GREEN (-3150 2700);
DISPLAY INVISIBLE (-3150 2700);
FORCEPROP 1 LAST HDL_TAP TRUE
J 0
(-2825 2625);
DISPLAY 1.234043 (-2825 2625);
PAINT GREEN (-2825 2625);
DISPLAY INVISIBLE (-2825 2625);
FORCEPROP 1 LAST PATH I244
J 0
(-3150 2750);
DISPLAY 0.936170 (-3150 2750);
PAINT GREEN (-3150 2750);
DISPLAY INVISIBLE (-3150 2750);
FORCEADD OFFPAGE..1
(-3800 2950);
FORCEPROP 2 LAST $XR0 23 
J 0
(-4021 2950);
DISPLAY 0.638298 (-4021 2950);
PAINT MONO (-4021 2950);
FORCEPROP 2 LAST $XR1 44 
J 0
(-4111 2950);
DISPLAY 0.638298 (-4111 2950);
PAINT MONO (-4111 2950);
FORCEPROP 2 LAST CDS_LIB mstr_standard
J 0
(-3800 2950);
DISPLAY 0.787234 (-3800 2950);
PAINT MONO (-3800 2950);
DISPLAY INVISIBLE (-3800 2950);
FORCEPROP 1 LAST OFFPAGE TRUE
J 0
(-3475 2825);
DISPLAY 0.936170 (-3475 2825);
PAINT GREEN (-3475 2825);
DISPLAY INVISIBLE (-3475 2825);
FORCEPROP 1 LAST COMMENT_BODY TRUE
J 0
(-3675 2850);
DISPLAY 0.936170 (-3675 2850);
PAINT GREEN (-3675 2850);
DISPLAY INVISIBLE (-3675 2850);
FORCEPROP 2 LAST PATH I245
J 0
(-3750 3025);
DISPLAY 0.787234 (-3750 3025);
PAINT MONO (-3750 3025);
DISPLAY INVISIBLE (-3750 3025);
FORCEADD TAP..6
(-3350 3050);
FORCEPROP 3 LASTPIN (-3300 3050) SIG_NAME M_A_CLK_DN<0>
J 0
(-3290 3060);
DISPLAY 0.659574 (-3290 3060);
PAINT MONO (-3290 3060);
DISPLAY INVISIBLE (-3290 3060);
FORCEPROP 1 LASTPIN (-3300 3050) BN 0
J 0
(-3350 3060);
DISPLAY 0.617021 (-3350 3060);
PAINT PINK (-3350 3060);
FORCEPROP 2 LAST CDS_LIB mstr_standard
J 0
(-3350 3050);
DISPLAY 0.787234 (-3350 3050);
PAINT MONO (-3350 3050);
DISPLAY INVISIBLE (-3350 3050);
FORCEPROP 1 LAST BODY_TYPE PLUMBING
J 0
(-3350 3000);
DISPLAY 1.234043 (-3350 3000);
PAINT GREEN (-3350 3000);
DISPLAY INVISIBLE (-3350 3000);
FORCEPROP 1 LAST HDL_TAP TRUE
J 0
(-3025 2925);
DISPLAY 1.234043 (-3025 2925);
PAINT GREEN (-3025 2925);
DISPLAY INVISIBLE (-3025 2925);
FORCEPROP 1 LAST PATH I247
J 0
(-3350 3050);
DISPLAY 0.936170 (-3350 3050);
PAINT GREEN (-3350 3050);
DISPLAY INVISIBLE (-3350 3050);
FORCEADD TAP..6
(-3150 4250);
FORCEPROP 3 LASTPIN (-3100 4250) SIG_NAME M_A_MA<14>
J 0
(-3090 4260);
DISPLAY 0.659574 (-3090 4260);
PAINT MONO (-3090 4260);
DISPLAY INVISIBLE (-3090 4260);
FORCEPROP 1 LASTPIN (-3100 4250) BN 14
J 0
(-3150 4260);
DISPLAY 0.617021 (-3150 4260);
PAINT PINK (-3150 4260);
FORCEPROP 2 LAST CDS_LIB mstr_standard
J 2
(-3150 4250);
DISPLAY 0.787234 (-3150 4250);
PAINT MONO (-3150 4250);
DISPLAY INVISIBLE (-3150 4250);
FORCEPROP 1 LAST BODY_TYPE PLUMBING
J 0
(-3150 4200);
DISPLAY 1.234043 (-3150 4200);
PAINT GREEN (-3150 4200);
DISPLAY INVISIBLE (-3150 4200);
FORCEPROP 1 LAST HDL_TAP TRUE
J 0
(-2825 4125);
DISPLAY 1.234043 (-2825 4125);
PAINT GREEN (-2825 4125);
DISPLAY INVISIBLE (-2825 4125);
FORCEPROP 1 LAST PATH I25
J 0
(-3150 4250);
DISPLAY 0.936170 (-3150 4250);
PAINT GREEN (-3150 4250);
DISPLAY INVISIBLE (-3150 4250);
FORCEADD TAP..6
(-3150 3200);
FORCEPROP 3 LASTPIN (-3100 3200) SIG_NAME M_A_CLK_DP<1>
J 0
(-3090 3210);
DISPLAY 0.659574 (-3090 3210);
PAINT MONO (-3090 3210);
DISPLAY INVISIBLE (-3090 3210);
FORCEPROP 1 LASTPIN (-3100 3200) BN 1
J 0
(-3150 3210);
DISPLAY 0.617021 (-3150 3210);
PAINT PINK (-3150 3210);
FORCEPROP 2 LAST CDS_LIB mstr_standard
J 0
(-3150 3200);
DISPLAY 0.787234 (-3150 3200);
PAINT MONO (-3150 3200);
DISPLAY INVISIBLE (-3150 3200);
FORCEPROP 1 LAST BODY_TYPE PLUMBING
J 0
(-3150 3150);
DISPLAY 1.234043 (-3150 3150);
PAINT GREEN (-3150 3150);
DISPLAY INVISIBLE (-3150 3150);
FORCEPROP 1 LAST HDL_TAP TRUE
J 0
(-2825 3075);
DISPLAY 1.234043 (-2825 3075);
PAINT GREEN (-2825 3075);
DISPLAY INVISIBLE (-2825 3075);
FORCEPROP 1 LAST PATH I250
J 0
(-3150 3200);
DISPLAY 0.936170 (-3150 3200);
PAINT GREEN (-3150 3200);
DISPLAY INVISIBLE (-3150 3200);
FORCEADD TAP..6
(-3150 3100);
FORCEPROP 3 LASTPIN (-3100 3100) SIG_NAME M_A_CLK_DP<0>
J 0
(-3090 3110);
DISPLAY 0.659574 (-3090 3110);
PAINT MONO (-3090 3110);
DISPLAY INVISIBLE (-3090 3110);
FORCEPROP 1 LASTPIN (-3100 3100) BN 0
J 0
(-3150 3110);
DISPLAY 0.617021 (-3150 3110);
PAINT PINK (-3150 3110);
FORCEPROP 2 LAST CDS_LIB mstr_standard
J 0
(-3150 3100);
DISPLAY 0.787234 (-3150 3100);
PAINT MONO (-3150 3100);
DISPLAY INVISIBLE (-3150 3100);
FORCEPROP 1 LAST BODY_TYPE PLUMBING
J 0
(-3150 3050);
DISPLAY 1.234043 (-3150 3050);
PAINT GREEN (-3150 3050);
DISPLAY INVISIBLE (-3150 3050);
FORCEPROP 1 LAST HDL_TAP TRUE
J 0
(-2825 2975);
DISPLAY 1.234043 (-2825 2975);
PAINT GREEN (-2825 2975);
DISPLAY INVISIBLE (-2825 2975);
FORCEPROP 1 LAST PATH I252
J 0
(-3150 3100);
DISPLAY 0.936170 (-3150 3100);
PAINT GREEN (-3150 3100);
DISPLAY INVISIBLE (-3150 3100);
FORCEADD TAP..6
(-3350 3150);
FORCEPROP 3 LASTPIN (-3300 3150) SIG_NAME M_A_CLK_DN<1>
J 0
(-3290 3160);
DISPLAY 0.659574 (-3290 3160);
PAINT MONO (-3290 3160);
DISPLAY INVISIBLE (-3290 3160);
FORCEPROP 1 LASTPIN (-3300 3150) BN 1
J 0
(-3350 3160);
DISPLAY 0.617021 (-3350 3160);
PAINT PINK (-3350 3160);
FORCEPROP 2 LAST CDS_LIB mstr_standard
J 0
(-3350 3150);
DISPLAY 0.787234 (-3350 3150);
PAINT MONO (-3350 3150);
DISPLAY INVISIBLE (-3350 3150);
FORCEPROP 1 LAST BODY_TYPE PLUMBING
J 0
(-3350 3100);
DISPLAY 1.234043 (-3350 3100);
PAINT GREEN (-3350 3100);
DISPLAY INVISIBLE (-3350 3100);
FORCEPROP 1 LAST HDL_TAP TRUE
J 0
(-3025 3025);
DISPLAY 1.234043 (-3025 3025);
PAINT GREEN (-3025 3025);
DISPLAY INVISIBLE (-3025 3025);
FORCEPROP 1 LAST PATH I254
J 0
(-3350 3150);
DISPLAY 0.936170 (-3350 3150);
PAINT GREEN (-3350 3150);
DISPLAY INVISIBLE (-3350 3150);
FORCEADD OFFPAGE..1
(-3800 3250);
FORCEPROP 2 LAST $XR0 23 
J 0
(-4021 3250);
DISPLAY 0.638298 (-4021 3250);
PAINT MONO (-4021 3250);
FORCEPROP 2 LAST $XR1 44 
J 0
(-4111 3250);
DISPLAY 0.638298 (-4111 3250);
PAINT MONO (-4111 3250);
FORCEPROP 2 LAST CDS_LIB mstr_standard
J 0
(-3800 3250);
DISPLAY 0.787234 (-3800 3250);
PAINT MONO (-3800 3250);
DISPLAY INVISIBLE (-3800 3250);
FORCEPROP 1 LAST OFFPAGE TRUE
J 0
(-3475 3125);
DISPLAY 0.936170 (-3475 3125);
PAINT GREEN (-3475 3125);
DISPLAY INVISIBLE (-3475 3125);
FORCEPROP 1 LAST COMMENT_BODY TRUE
J 0
(-3675 3150);
DISPLAY 0.936170 (-3675 3150);
PAINT GREEN (-3675 3150);
DISPLAY INVISIBLE (-3675 3150);
FORCEPROP 2 LAST PATH I255
J 0
(-3750 3325);
DISPLAY 0.787234 (-3750 3325);
PAINT MONO (-3750 3325);
DISPLAY INVISIBLE (-3750 3325);
FORCEADD OFFPAGE..1
(-3800 3200);
FORCEPROP 2 LAST $XR0 23 
J 0
(-4021 3200);
DISPLAY 0.638298 (-4021 3200);
PAINT MONO (-4021 3200);
FORCEPROP 2 LAST $XR1 44 
J 0
(-4111 3200);
DISPLAY 0.638298 (-4111 3200);
PAINT MONO (-4111 3200);
FORCEPROP 2 LAST CDS_LIB mstr_standard
J 0
(-3800 3200);
DISPLAY 0.787234 (-3800 3200);
PAINT MONO (-3800 3200);
DISPLAY INVISIBLE (-3800 3200);
FORCEPROP 1 LAST OFFPAGE TRUE
J 0
(-3475 3075);
DISPLAY 0.936170 (-3475 3075);
PAINT GREEN (-3475 3075);
DISPLAY INVISIBLE (-3475 3075);
FORCEPROP 1 LAST COMMENT_BODY TRUE
J 0
(-3675 3100);
DISPLAY 0.936170 (-3675 3100);
PAINT GREEN (-3675 3100);
DISPLAY INVISIBLE (-3675 3100);
FORCEPROP 2 LAST PATH I256
J 0
(-3750 3275);
DISPLAY 0.787234 (-3750 3275);
PAINT MONO (-3750 3275);
DISPLAY INVISIBLE (-3750 3275);
FORCEADD OFFPAGE..1
(-3800 1350);
FORCEPROP 2 LAST $XR0 99 
J 0
(-4051 1350);
DISPLAY 0.638298 (-4051 1350);
PAINT MONO (-4051 1350);
FORCEPROP 2 LAST $XR1 44 
J 0
(-4141 1350);
DISPLAY 0.638298 (-4141 1350);
PAINT MONO (-4141 1350);
FORCEPROP 2 LAST $XR2 45 
J 0
(-4231 1350);
DISPLAY 0.638298 (-4231 1350);
PAINT MONO (-4231 1350);
FORCEPROP 2 LAST $XR3 46 
J 0
(-4321 1350);
DISPLAY 0.638298 (-4321 1350);
PAINT MONO (-4321 1350);
FORCEPROP 2 LAST $XR4 47 
J 0
(-4411 1350);
DISPLAY 0.638298 (-4411 1350);
PAINT MONO (-4411 1350);
FORCEPROP 2 LAST $XR5 48 
J 0
(-4501 1350);
DISPLAY 0.638298 (-4501 1350);
PAINT MONO (-4501 1350);
FORCEPROP 2 LAST CDS_LIB mstr_standard
J 0
(-3800 1350);
DISPLAY 0.787234 (-3800 1350);
PAINT MONO (-3800 1350);
DISPLAY INVISIBLE (-3800 1350);
FORCEPROP 1 LAST OFFPAGE TRUE
J 0
(-3475 1225);
DISPLAY 0.936170 (-3475 1225);
PAINT GREEN (-3475 1225);
DISPLAY INVISIBLE (-3475 1225);
FORCEPROP 1 LAST COMMENT_BODY TRUE
J 0
(-3675 1250);
DISPLAY 0.936170 (-3675 1250);
PAINT GREEN (-3675 1250);
DISPLAY INVISIBLE (-3675 1250);
FORCEPROP 2 LAST PATH I257
J 0
(-3750 1425);
DISPLAY 0.787234 (-3750 1425);
PAINT MONO (-3750 1425);
DISPLAY INVISIBLE (-3750 1425);
FORCEADD OFFPAGE..6
(-3800 1400);
FORCEPROP 2 LAST $XR0 44 
J 0
(-4049 1400);
DISPLAY 0.638298 (-4049 1400);
PAINT MONO (-4049 1400);
FORCEPROP 2 LAST $XR1 45 
J 0
(-4139 1400);
DISPLAY 0.638298 (-4139 1400);
PAINT MONO (-4139 1400);
FORCEPROP 2 LAST $XR2 46 
J 0
(-4229 1400);
DISPLAY 0.638298 (-4229 1400);
PAINT MONO (-4229 1400);
FORCEPROP 2 LAST $XR3 47 
J 0
(-4319 1400);
DISPLAY 0.638298 (-4319 1400);
PAINT MONO (-4319 1400);
FORCEPROP 2 LAST $XR4 48 
J 0
(-4409 1400);
DISPLAY 0.638298 (-4409 1400);
PAINT MONO (-4409 1400);
FORCEPROP 2 LAST $XR5 99 
J 0
(-4499 1400);
DISPLAY 0.638298 (-4499 1400);
PAINT MONO (-4499 1400);
FORCEPROP 2 LASTPIN (-3750 1400) SIG_NAME SMB_DDR_ABC_VPP_SDA
J 0
(-3710 1410);
DISPLAY 0.617021 (-3710 1410);
PAINT ORANGE (-3710 1410);
FORCEPROP 2 LAST CDS_LIB mstr_standard
J 0
(-3800 1400);
DISPLAY 0.787234 (-3800 1400);
PAINT MONO (-3800 1400);
DISPLAY INVISIBLE (-3800 1400);
FORCEPROP 1 LAST OFFPAGE TRUE
J 0
(-3475 1275);
DISPLAY 0.936170 (-3475 1275);
PAINT GREEN (-3475 1275);
DISPLAY INVISIBLE (-3475 1275);
FORCEPROP 1 LAST COMMENT_BODY TRUE
J 0
(-3700 1325);
DISPLAY 0.936170 (-3700 1325);
PAINT GREEN (-3700 1325);
DISPLAY INVISIBLE (-3700 1325);
FORCEPROP 2 LAST PATH I258
J 0
(-3750 1475);
DISPLAY 0.787234 (-3750 1475);
PAINT MONO (-3750 1475);
DISPLAY INVISIBLE (-3750 1475);
FORCEADD SCONN288_H44441004..3
(1750 2450);
FORCEPROP 1 LAST LOCATION J4G1
J 0
(1300 3850);
DISPLAY 0.617021 (1300 3850);
PAINT AQUA (1300 3850);
FORCEPROP 1 LAST PART_NUMBER H44441-004
J 0
(1300 1100);
DISPLAY 0.617021 (1300 1100);
PAINT BLUE (1300 1100);
FORCEPROP 1 LAST MATERIAL SCONN
J 0
(1300 3800);
DISPLAY 0.617021 (1300 3800);
PAINT SKYBLUE (1300 3800);
FORCEPROP 2 LASTPIN (1250 3600) $PN 2
J 2
(1240 3610);
DISPLAY 0.617021 (1240 3610);
PAINT ORANGE (1240 3610);
FORCEPROP 2 LASTPIN (1250 3550) $PN 4
J 2
(1240 3560);
DISPLAY 0.617021 (1240 3560);
PAINT ORANGE (1240 3560);
FORCEPROP 2 LASTPIN (1250 3500) $PN 6
J 2
(1240 3510);
DISPLAY 0.617021 (1240 3510);
PAINT ORANGE (1240 3510);
FORCEPROP 2 LASTPIN (1250 3450) $PN 9
J 2
(1240 3460);
DISPLAY 0.617021 (1240 3460);
PAINT ORANGE (1240 3460);
FORCEPROP 2 LASTPIN (1250 3400) $PN 11
J 2
(1240 3410);
DISPLAY 0.617021 (1240 3410);
PAINT ORANGE (1240 3410);
FORCEPROP 2 LASTPIN (1250 3350) $PN 13
J 2
(1240 3360);
DISPLAY 0.617021 (1240 3360);
PAINT ORANGE (1240 3360);
FORCEPROP 2 LASTPIN (1250 3300) $PN 15
J 2
(1240 3310);
DISPLAY 0.617021 (1240 3310);
PAINT ORANGE (1240 3310);
FORCEPROP 2 LASTPIN (1250 3250) $PN 17
J 2
(1240 3260);
DISPLAY 0.617021 (1240 3260);
PAINT ORANGE (1240 3260);
FORCEPROP 2 LASTPIN (1250 3200) $PN 20
J 2
(1240 3210);
DISPLAY 0.617021 (1240 3210);
PAINT ORANGE (1240 3210);
FORCEPROP 2 LASTPIN (1250 3150) $PN 22
J 2
(1240 3160);
DISPLAY 0.617021 (1240 3160);
PAINT ORANGE (1240 3160);
FORCEPROP 2 LASTPIN (1250 3100) $PN 24
J 2
(1240 3110);
DISPLAY 0.617021 (1240 3110);
PAINT ORANGE (1240 3110);
FORCEPROP 2 LASTPIN (1250 3050) $PN 26
J 2
(1240 3060);
DISPLAY 0.617021 (1240 3060);
PAINT ORANGE (1240 3060);
FORCEPROP 2 LASTPIN (1250 3000) $PN 28
J 2
(1240 3010);
DISPLAY 0.617021 (1240 3010);
PAINT ORANGE (1240 3010);
FORCEPROP 2 LASTPIN (1250 2950) $PN 31
J 2
(1240 2960);
DISPLAY 0.617021 (1240 2960);
PAINT ORANGE (1240 2960);
FORCEPROP 2 LASTPIN (1250 2900) $PN 33
J 2
(1240 2910);
DISPLAY 0.617021 (1240 2910);
PAINT ORANGE (1240 2910);
FORCEPROP 2 LASTPIN (1250 2850) $PN 35
J 2
(1240 2860);
DISPLAY 0.617021 (1240 2860);
PAINT ORANGE (1240 2860);
FORCEPROP 2 LASTPIN (1250 2800) $PN 37
J 2
(1240 2810);
DISPLAY 0.617021 (1240 2810);
PAINT ORANGE (1240 2810);
FORCEPROP 2 LASTPIN (1250 2750) $PN 39
J 2
(1240 2760);
DISPLAY 0.617021 (1240 2760);
PAINT ORANGE (1240 2760);
FORCEPROP 2 LASTPIN (1250 2700) $PN 42
J 2
(1240 2710);
DISPLAY 0.617021 (1240 2710);
PAINT ORANGE (1240 2710);
FORCEPROP 2 LASTPIN (1250 2650) $PN 44
J 2
(1240 2660);
DISPLAY 0.617021 (1240 2660);
PAINT ORANGE (1240 2660);
FORCEPROP 2 LASTPIN (1250 2600) $PN 46
J 2
(1240 2610);
DISPLAY 0.617021 (1240 2610);
PAINT ORANGE (1240 2610);
FORCEPROP 2 LASTPIN (1250 2550) $PN 48
J 2
(1240 2560);
DISPLAY 0.617021 (1240 2560);
PAINT ORANGE (1240 2560);
FORCEPROP 2 LASTPIN (1250 2500) $PN 50
J 2
(1240 2510);
DISPLAY 0.617021 (1240 2510);
PAINT ORANGE (1240 2510);
FORCEPROP 2 LASTPIN (1250 2450) $PN 53
J 2
(1240 2460);
DISPLAY 0.617021 (1240 2460);
PAINT ORANGE (1240 2460);
FORCEPROP 2 LASTPIN (1250 2400) $PN 55
J 2
(1240 2410);
DISPLAY 0.617021 (1240 2410);
PAINT ORANGE (1240 2410);
FORCEPROP 2 LASTPIN (1250 2350) $PN 57
J 2
(1240 2360);
DISPLAY 0.617021 (1240 2360);
PAINT ORANGE (1240 2360);
FORCEPROP 2 LASTPIN (1250 2300) $PN 94
J 2
(1240 2310);
DISPLAY 0.617021 (1240 2310);
PAINT ORANGE (1240 2310);
FORCEPROP 2 LASTPIN (1250 2250) $PN 96
J 2
(1240 2260);
DISPLAY 0.617021 (1240 2260);
PAINT ORANGE (1240 2260);
FORCEPROP 2 LASTPIN (1250 2200) $PN 98
J 2
(1240 2210);
DISPLAY 0.617021 (1240 2210);
PAINT ORANGE (1240 2210);
FORCEPROP 2 LASTPIN (1250 2150) $PN 101
J 2
(1240 2160);
DISPLAY 0.617021 (1240 2160);
PAINT ORANGE (1240 2160);
FORCEPROP 2 LASTPIN (1250 2100) $PN 103
J 2
(1240 2110);
DISPLAY 0.617021 (1240 2110);
PAINT ORANGE (1240 2110);
FORCEPROP 2 LASTPIN (1250 2050) $PN 105
J 2
(1240 2060);
DISPLAY 0.617021 (1240 2060);
PAINT ORANGE (1240 2060);
FORCEPROP 2 LASTPIN (1250 2000) $PN 107
J 2
(1240 2010);
DISPLAY 0.617021 (1240 2010);
PAINT ORANGE (1240 2010);
FORCEPROP 2 LASTPIN (1250 1950) $PN 109
J 2
(1240 1960);
DISPLAY 0.617021 (1240 1960);
PAINT ORANGE (1240 1960);
FORCEPROP 2 LASTPIN (1250 1900) $PN 112
J 2
(1240 1910);
DISPLAY 0.617021 (1240 1910);
PAINT ORANGE (1240 1910);
FORCEPROP 2 LASTPIN (1250 1850) $PN 114
J 2
(1240 1860);
DISPLAY 0.617021 (1240 1860);
PAINT ORANGE (1240 1860);
FORCEPROP 2 LASTPIN (1250 1800) $PN 116
J 2
(1240 1810);
DISPLAY 0.617021 (1240 1810);
PAINT ORANGE (1240 1810);
FORCEPROP 2 LASTPIN (1250 1750) $PN 118
J 2
(1240 1760);
DISPLAY 0.617021 (1240 1760);
PAINT ORANGE (1240 1760);
FORCEPROP 2 LASTPIN (1250 1700) $PN 120
J 2
(1240 1710);
DISPLAY 0.617021 (1240 1710);
PAINT ORANGE (1240 1710);
FORCEPROP 2 LASTPIN (1250 1650) $PN 123
J 2
(1240 1660);
DISPLAY 0.617021 (1240 1660);
PAINT ORANGE (1240 1660);
FORCEPROP 2 LASTPIN (1250 1600) $PN 125
J 2
(1240 1610);
DISPLAY 0.617021 (1240 1610);
PAINT ORANGE (1240 1610);
FORCEPROP 2 LASTPIN (1250 1550) $PN 127
J 2
(1240 1560);
DISPLAY 0.617021 (1240 1560);
PAINT ORANGE (1240 1560);
FORCEPROP 2 LASTPIN (1250 1500) $PN 129
J 2
(1240 1510);
DISPLAY 0.617021 (1240 1510);
PAINT ORANGE (1240 1510);
FORCEPROP 2 LASTPIN (1250 1450) $PN 131
J 2
(1240 1460);
DISPLAY 0.617021 (1240 1460);
PAINT ORANGE (1240 1460);
FORCEPROP 2 LASTPIN (1250 1400) $PN 134
J 2
(1240 1410);
DISPLAY 0.617021 (1240 1410);
PAINT ORANGE (1240 1410);
FORCEPROP 2 LASTPIN (1250 1350) $PN 136
J 2
(1240 1360);
DISPLAY 0.617021 (1240 1360);
PAINT ORANGE (1240 1360);
FORCEPROP 2 LASTPIN (1250 1300) $PN 138
J 2
(1240 1310);
DISPLAY 0.617021 (1240 1310);
PAINT ORANGE (1240 1310);
FORCEPROP 2 LASTPIN (2250 3600) $PN 147
J 0
(2260 3610);
DISPLAY 0.617021 (2260 3610);
PAINT ORANGE (2260 3610);
FORCEPROP 2 LASTPIN (2250 3550) $PN 149
J 0
(2260 3560);
DISPLAY 0.617021 (2260 3560);
PAINT ORANGE (2260 3560);
FORCEPROP 2 LASTPIN (2250 3500) $PN 151
J 0
(2260 3510);
DISPLAY 0.617021 (2260 3510);
PAINT ORANGE (2260 3510);
FORCEPROP 2 LASTPIN (2250 3450) $PN 154
J 0
(2260 3460);
DISPLAY 0.617021 (2260 3460);
PAINT ORANGE (2260 3460);
FORCEPROP 2 LASTPIN (2250 3400) $PN 156
J 0
(2260 3410);
DISPLAY 0.617021 (2260 3410);
PAINT ORANGE (2260 3410);
FORCEPROP 2 LASTPIN (2250 3350) $PN 158
J 0
(2260 3360);
DISPLAY 0.617021 (2260 3360);
PAINT ORANGE (2260 3360);
FORCEPROP 2 LASTPIN (2250 3300) $PN 160
J 0
(2260 3310);
DISPLAY 0.617021 (2260 3310);
PAINT ORANGE (2260 3310);
FORCEPROP 2 LASTPIN (2250 3250) $PN 162
J 0
(2260 3260);
DISPLAY 0.617021 (2260 3260);
PAINT ORANGE (2260 3260);
FORCEPROP 2 LASTPIN (2250 3200) $PN 165
J 0
(2260 3210);
DISPLAY 0.617021 (2260 3210);
PAINT ORANGE (2260 3210);
FORCEPROP 2 LASTPIN (2250 3150) $PN 167
J 0
(2260 3160);
DISPLAY 0.617021 (2260 3160);
PAINT ORANGE (2260 3160);
FORCEPROP 2 LASTPIN (2250 3100) $PN 169
J 0
(2260 3110);
DISPLAY 0.617021 (2260 3110);
PAINT ORANGE (2260 3110);
FORCEPROP 2 LASTPIN (2250 3050) $PN 171
J 0
(2260 3060);
DISPLAY 0.617021 (2260 3060);
PAINT ORANGE (2260 3060);
FORCEPROP 2 LASTPIN (2250 3000) $PN 173
J 0
(2260 3010);
DISPLAY 0.617021 (2260 3010);
PAINT ORANGE (2260 3010);
FORCEPROP 2 LASTPIN (2250 2950) $PN 176
J 0
(2260 2960);
DISPLAY 0.617021 (2260 2960);
PAINT ORANGE (2260 2960);
FORCEPROP 2 LASTPIN (2250 2900) $PN 178
J 0
(2260 2910);
DISPLAY 0.617021 (2260 2910);
PAINT ORANGE (2260 2910);
FORCEPROP 2 LASTPIN (2250 2850) $PN 180
J 0
(2260 2860);
DISPLAY 0.617021 (2260 2860);
PAINT ORANGE (2260 2860);
FORCEPROP 2 LASTPIN (2250 2800) $PN 182
J 0
(2260 2810);
DISPLAY 0.617021 (2260 2810);
PAINT ORANGE (2260 2810);
FORCEPROP 2 LASTPIN (2250 2750) $PN 184
J 0
(2260 2760);
DISPLAY 0.617021 (2260 2760);
PAINT ORANGE (2260 2760);
FORCEPROP 2 LASTPIN (2250 2700) $PN 187
J 0
(2260 2710);
DISPLAY 0.617021 (2260 2710);
PAINT ORANGE (2260 2710);
FORCEPROP 2 LASTPIN (2250 2650) $PN 189
J 0
(2260 2660);
DISPLAY 0.617021 (2260 2660);
PAINT ORANGE (2260 2660);
FORCEPROP 2 LASTPIN (2250 2600) $PN 191
J 0
(2260 2610);
DISPLAY 0.617021 (2260 2610);
PAINT ORANGE (2260 2610);
FORCEPROP 2 LASTPIN (2250 2550) $PN 193
J 0
(2260 2560);
DISPLAY 0.617021 (2260 2560);
PAINT ORANGE (2260 2560);
FORCEPROP 2 LASTPIN (2250 2500) $PN 195
J 0
(2260 2510);
DISPLAY 0.617021 (2260 2510);
PAINT ORANGE (2260 2510);
FORCEPROP 2 LASTPIN (2250 2450) $PN 198
J 0
(2260 2460);
DISPLAY 0.617021 (2260 2460);
PAINT ORANGE (2260 2460);
FORCEPROP 2 LASTPIN (2250 2400) $PN 200
J 0
(2260 2410);
DISPLAY 0.617021 (2260 2410);
PAINT ORANGE (2260 2410);
FORCEPROP 2 LASTPIN (2250 2350) $PN 202
J 0
(2260 2360);
DISPLAY 0.617021 (2260 2360);
PAINT ORANGE (2260 2360);
FORCEPROP 2 LASTPIN (2250 2300) $PN 239
J 0
(2260 2310);
DISPLAY 0.617021 (2260 2310);
PAINT ORANGE (2260 2310);
FORCEPROP 2 LASTPIN (2250 2250) $PN 241
J 0
(2260 2260);
DISPLAY 0.617021 (2260 2260);
PAINT ORANGE (2260 2260);
FORCEPROP 2 LASTPIN (2250 2200) $PN 243
J 0
(2260 2210);
DISPLAY 0.617021 (2260 2210);
PAINT ORANGE (2260 2210);
FORCEPROP 2 LASTPIN (2250 2150) $PN 246
J 0
(2260 2160);
DISPLAY 0.617021 (2260 2160);
PAINT ORANGE (2260 2160);
FORCEPROP 2 LASTPIN (2250 2100) $PN 248
J 0
(2260 2110);
DISPLAY 0.617021 (2260 2110);
PAINT ORANGE (2260 2110);
FORCEPROP 2 LASTPIN (2250 2050) $PN 250
J 0
(2260 2060);
DISPLAY 0.617021 (2260 2060);
PAINT ORANGE (2260 2060);
FORCEPROP 2 LASTPIN (2250 2000) $PN 252
J 0
(2260 2010);
DISPLAY 0.617021 (2260 2010);
PAINT ORANGE (2260 2010);
FORCEPROP 2 LASTPIN (2250 1950) $PN 254
J 0
(2260 1960);
DISPLAY 0.617021 (2260 1960);
PAINT ORANGE (2260 1960);
FORCEPROP 2 LASTPIN (2250 1900) $PN 257
J 0
(2260 1910);
DISPLAY 0.617021 (2260 1910);
PAINT ORANGE (2260 1910);
FORCEPROP 2 LASTPIN (2250 1850) $PN 259
J 0
(2260 1860);
DISPLAY 0.617021 (2260 1860);
PAINT ORANGE (2260 1860);
FORCEPROP 2 LASTPIN (2250 1800) $PN 261
J 0
(2260 1810);
DISPLAY 0.617021 (2260 1810);
PAINT ORANGE (2260 1810);
FORCEPROP 2 LASTPIN (2250 1750) $PN 263
J 0
(2260 1760);
DISPLAY 0.617021 (2260 1760);
PAINT ORANGE (2260 1760);
FORCEPROP 2 LASTPIN (2250 1700) $PN 265
J 0
(2260 1710);
DISPLAY 0.617021 (2260 1710);
PAINT ORANGE (2260 1710);
FORCEPROP 2 LASTPIN (2250 1650) $PN 268
J 0
(2260 1660);
DISPLAY 0.617021 (2260 1660);
PAINT ORANGE (2260 1660);
FORCEPROP 2 LASTPIN (2250 1600) $PN 270
J 0
(2260 1610);
DISPLAY 0.617021 (2260 1610);
PAINT ORANGE (2260 1610);
FORCEPROP 2 LASTPIN (2250 1550) $PN 272
J 0
(2260 1560);
DISPLAY 0.617021 (2260 1560);
PAINT ORANGE (2260 1560);
FORCEPROP 2 LASTPIN (2250 1500) $PN 274
J 0
(2260 1510);
DISPLAY 0.617021 (2260 1510);
PAINT ORANGE (2260 1510);
FORCEPROP 2 LASTPIN (2250 1450) $PN 276
J 0
(2260 1460);
DISPLAY 0.617021 (2260 1460);
PAINT ORANGE (2260 1460);
FORCEPROP 2 LASTPIN (2250 1400) $PN 279
J 0
(2260 1410);
DISPLAY 0.617021 (2260 1410);
PAINT ORANGE (2260 1410);
FORCEPROP 2 LASTPIN (2250 1350) $PN 281
J 0
(2260 1360);
DISPLAY 0.617021 (2260 1360);
PAINT ORANGE (2260 1360);
FORCEPROP 2 LASTPIN (2250 1300) $PN 283
J 0
(2260 1310);
DISPLAY 0.617021 (2260 1310);
PAINT ORANGE (2260 1310);
FORCEPROP 1 LAST PACK_TYPE PIP
J 0
(1300 3900);
PAINT SKYBLUE (1300 3900);
DISPLAY INVISIBLE (1300 3900);
FORCEPROP 2 LAST BOM_COST MEM
J 0
(1750 2450);
PAINT ORANGE (1750 2450);
DISPLAY INVISIBLE (1750 2450);
FORCEPROP 2 LAST CDS_LIB mstr_sconn
J 0
(1750 2450);
PAINT ORANGE (1750 2450);
DISPLAY INVISIBLE (1750 2450);
FORCEPROP 2 LAST SEC_TYPE PIP
J 0
(1300 3900);
DISPLAY 1.021277 (1300 3900);
PAINT ORANGE (1300 3900);
DISPLAY INVISIBLE (1300 3900);
FORCEPROP 2 LAST SEC 3
J 0
(1300 3900);
DISPLAY 0.680851 (1300 3900);
PAINT MONO (1300 3900);
DISPLAY INVISIBLE (1300 3900);
FORCEPROP 2 LAST CDS_LOCATION J4G1
J 0
(1300 3850);
DISPLAY 0.617021 (1300 3850);
PAINT AQUA (1300 3850);
DISPLAY INVISIBLE (1300 3850);
FORCEPROP 1 LAST PATH I259
J 0
(1750 3800);
PAINT GREEN (1750 3800);
DISPLAY INVISIBLE (1750 3800);
FORCEPROP 2 LAST ROOM DDR4_CH_A
J 0
(1750 2450);
PAINT ORANGE (1750 2450);
DISPLAY INVISIBLE (1750 2450);
FORCEADD TAP..6
(-3150 4200);
FORCEPROP 3 LASTPIN (-3100 4200) SIG_NAME M_A_MA<13>
J 0
(-3090 4210);
DISPLAY 0.659574 (-3090 4210);
PAINT MONO (-3090 4210);
DISPLAY INVISIBLE (-3090 4210);
FORCEPROP 1 LASTPIN (-3100 4200) BN 13
J 0
(-3150 4210);
DISPLAY 0.617021 (-3150 4210);
PAINT PINK (-3150 4210);
FORCEPROP 2 LAST CDS_LIB mstr_standard
J 2
(-3150 4200);
DISPLAY 0.787234 (-3150 4200);
PAINT MONO (-3150 4200);
DISPLAY INVISIBLE (-3150 4200);
FORCEPROP 1 LAST BODY_TYPE PLUMBING
J 0
(-3150 4150);
DISPLAY 1.234043 (-3150 4150);
PAINT GREEN (-3150 4150);
DISPLAY INVISIBLE (-3150 4150);
FORCEPROP 1 LAST HDL_TAP TRUE
J 0
(-2825 4075);
DISPLAY 1.234043 (-2825 4075);
PAINT GREEN (-2825 4075);
DISPLAY INVISIBLE (-2825 4075);
FORCEPROP 1 LAST PATH I26
J 0
(-3150 4200);
DISPLAY 0.936170 (-3150 4200);
PAINT GREEN (-3150 4200);
DISPLAY INVISIBLE (-3150 4200);
FORCEADD SCONN288_H44441004..4
(-100 1700);
FORCEPROP 1 LAST LOCATION J4G1
J 0
(-550 2800);
DISPLAY 0.617021 (-550 2800);
PAINT AQUA (-550 2800);
FORCEPROP 1 LAST PART_NUMBER H44441-004
J 0
(-550 650);
DISPLAY 0.617021 (-550 650);
PAINT BLUE (-550 650);
FORCEPROP 1 LAST MATERIAL SCONN
J 0
(-550 2750);
DISPLAY 0.617021 (-550 2750);
PAINT SKYBLUE (-550 2750);
FORCEPROP 2 LASTPIN (-600 2250) $PN 77
J 2
(-610 2260);
DISPLAY 0.617021 (-610 2260);
PAINT ORANGE (-610 2260);
FORCEPROP 2 LASTPIN (-600 2200) $PN 221
J 2
(-610 2210);
DISPLAY 0.617021 (-610 2210);
PAINT ORANGE (-610 2210);
FORCEPROP 2 LASTPIN (-600 2550) $PN 142
J 2
(-610 2560);
DISPLAY 0.617021 (-610 2560);
PAINT ORANGE (-610 2560);
FORCEPROP 2 LASTPIN (-600 2500) $PN 143
J 2
(-610 2510);
DISPLAY 0.617021 (-610 2510);
PAINT ORANGE (-610 2510);
FORCEPROP 2 LASTPIN (-600 2450) $PN 288
J 2
(-610 2460);
DISPLAY 0.617021 (-610 2460);
PAINT ORANGE (-610 2460);
FORCEPROP 2 LASTPIN (-600 2400) $PN 286
J 2
(-610 2410);
DISPLAY 0.617021 (-610 2410);
PAINT ORANGE (-610 2410);
FORCEPROP 2 LASTPIN (-600 2350) $PN 287
J 2
(-610 2360);
DISPLAY 0.617021 (-610 2360);
PAINT ORANGE (-610 2360);
FORCEPROP 2 LASTPIN (-600 2100) $PN 59
J 2
(-610 2110);
DISPLAY 0.617021 (-610 2110);
PAINT ORANGE (-610 2110);
FORCEPROP 2 LASTPIN (-600 2050) $PN 61
J 2
(-610 2060);
DISPLAY 0.617021 (-610 2060);
PAINT ORANGE (-610 2060);
FORCEPROP 2 LASTPIN (-600 2000) $PN 64
J 2
(-610 2010);
DISPLAY 0.617021 (-610 2010);
PAINT ORANGE (-610 2010);
FORCEPROP 2 LASTPIN (-600 1950) $PN 67
J 2
(-610 1960);
DISPLAY 0.617021 (-610 1960);
PAINT ORANGE (-610 1960);
FORCEPROP 2 LASTPIN (-600 1900) $PN 70
J 2
(-610 1910);
DISPLAY 0.617021 (-610 1910);
PAINT ORANGE (-610 1910);
FORCEPROP 2 LASTPIN (-600 1850) $PN 73
J 2
(-610 1860);
DISPLAY 0.617021 (-610 1860);
PAINT ORANGE (-610 1860);
FORCEPROP 2 LASTPIN (-600 1800) $PN 76
J 2
(-610 1810);
DISPLAY 0.617021 (-610 1810);
PAINT ORANGE (-610 1810);
FORCEPROP 2 LASTPIN (-600 1750) $PN 80
J 2
(-610 1760);
DISPLAY 0.617021 (-610 1760);
PAINT ORANGE (-610 1760);
FORCEPROP 2 LASTPIN (-600 1700) $PN 83
J 2
(-610 1710);
DISPLAY 0.617021 (-610 1710);
PAINT ORANGE (-610 1710);
FORCEPROP 2 LASTPIN (-600 1650) $PN 85
J 2
(-610 1660);
DISPLAY 0.617021 (-610 1660);
PAINT ORANGE (-610 1660);
FORCEPROP 2 LASTPIN (-600 1600) $PN 88
J 2
(-610 1610);
DISPLAY 0.617021 (-610 1610);
PAINT ORANGE (-610 1610);
FORCEPROP 2 LASTPIN (-600 1550) $PN 90
J 2
(-610 1560);
DISPLAY 0.617021 (-610 1560);
PAINT ORANGE (-610 1560);
FORCEPROP 2 LASTPIN (-600 1500) $PN 92
J 2
(-610 1510);
DISPLAY 0.617021 (-610 1510);
PAINT ORANGE (-610 1510);
FORCEPROP 2 LASTPIN (-600 1450) $PN 204
J 2
(-610 1460);
DISPLAY 0.617021 (-610 1460);
PAINT ORANGE (-610 1460);
FORCEPROP 2 LASTPIN (-600 1400) $PN 206
J 2
(-610 1410);
DISPLAY 0.617021 (-610 1410);
PAINT ORANGE (-610 1410);
FORCEPROP 2 LASTPIN (-600 1350) $PN 209
J 2
(-610 1360);
DISPLAY 0.617021 (-610 1360);
PAINT ORANGE (-610 1360);
FORCEPROP 2 LASTPIN (-600 1300) $PN 212
J 2
(-610 1310);
DISPLAY 0.617021 (-610 1310);
PAINT ORANGE (-610 1310);
FORCEPROP 2 LASTPIN (-600 1250) $PN 215
J 2
(-610 1260);
DISPLAY 0.617021 (-610 1260);
PAINT ORANGE (-610 1260);
FORCEPROP 2 LASTPIN (-600 1200) $PN 217
J 2
(-610 1210);
DISPLAY 0.617021 (-610 1210);
PAINT ORANGE (-610 1210);
FORCEPROP 2 LASTPIN (-600 1150) $PN 220
J 2
(-610 1160);
DISPLAY 0.617021 (-610 1160);
PAINT ORANGE (-610 1160);
FORCEPROP 2 LASTPIN (-600 1100) $PN 223
J 2
(-610 1110);
DISPLAY 0.617021 (-610 1110);
PAINT ORANGE (-610 1110);
FORCEPROP 2 LASTPIN (-600 1050) $PN 226
J 2
(-610 1060);
DISPLAY 0.617021 (-610 1060);
PAINT ORANGE (-610 1060);
FORCEPROP 2 LASTPIN (-600 1000) $PN 229
J 2
(-610 1010);
DISPLAY 0.617021 (-610 1010);
PAINT ORANGE (-610 1010);
FORCEPROP 2 LASTPIN (-600 950) $PN 231
J 2
(-610 960);
DISPLAY 0.617021 (-610 960);
PAINT ORANGE (-610 960);
FORCEPROP 2 LASTPIN (-600 900) $PN 233
J 2
(-610 910);
DISPLAY 0.617021 (-610 910);
PAINT ORANGE (-610 910);
FORCEPROP 2 LASTPIN (-600 850) $PN 236
J 2
(-610 860);
DISPLAY 0.617021 (-610 860);
PAINT ORANGE (-610 860);
FORCEPROP 2 LASTPIN (400 2550) $PN 1
J 0
(410 2560);
DISPLAY 0.617021 (410 2560);
PAINT ORANGE (410 2560);
FORCEPROP 2 LASTPIN (400 2500) $PN 145
J 0
(410 2510);
DISPLAY 0.617021 (410 2510);
PAINT ORANGE (410 2510);
FORCEPROP 1 LAST PACK_TYPE PIP
J 0
(-550 2850);
PAINT SKYBLUE (-550 2850);
DISPLAY INVISIBLE (-550 2850);
FORCEPROP 2 LAST BOM_COST MEM
J 0
(-100 1700);
PAINT ORANGE (-100 1700);
DISPLAY INVISIBLE (-100 1700);
FORCEPROP 2 LAST CDS_LIB mstr_sconn
J 0
(-100 1700);
PAINT ORANGE (-100 1700);
DISPLAY INVISIBLE (-100 1700);
FORCEPROP 2 LAST SEC_TYPE PIP
J 0
(-550 2850);
DISPLAY 1.021277 (-550 2850);
PAINT ORANGE (-550 2850);
DISPLAY INVISIBLE (-550 2850);
FORCEPROP 2 LAST SEC 4
J 0
(-550 2850);
DISPLAY 0.680851 (-550 2850);
PAINT MONO (-550 2850);
DISPLAY INVISIBLE (-550 2850);
FORCEPROP 2 LAST CDS_LOCATION J4G1
J 0
(-550 2800);
DISPLAY 0.617021 (-550 2800);
PAINT AQUA (-550 2800);
DISPLAY INVISIBLE (-550 2800);
FORCEPROP 1 LAST PATH I260
J 0
(-100 2750);
PAINT GREEN (-100 2750);
DISPLAY INVISIBLE (-100 2750);
FORCEPROP 2 LAST ROOM DDR4_CH_A
J 0
(-100 1700);
PAINT ORANGE (-100 1700);
DISPLAY INVISIBLE (-100 1700);
FORCEADD PVDDQ_ABC..1
(-1125 2250);
FORCEPROP 3 LASTPIN (-1125 2200) SIG_NAME PVDDQ_ABC\g
J 0
(-1115 2210);
DISPLAY 0.659574 (-1115 2210);
PAINT MONO (-1115 2210);
DISPLAY INVISIBLE (-1115 2210);
FORCEPROP 1 LAST VOLTAGE 1.2V
J 0
(-1170 2207);
DISPLAY 0.340426 (-1170 2207);
PAINT SKYBLUE (-1170 2207);
DISPLAY INVISIBLE (-1170 2207);
FORCEPROP 2 LAST BOM_COST MEM
J 0
(-1125 2255);
PAINT ORANGE (-1125 2255);
DISPLAY INVISIBLE (-1125 2255);
FORCEPROP 2 LAST CDS_LIB mstr_symbols
J 0
(-1125 2250);
PAINT ORANGE (-1125 2250);
DISPLAY INVISIBLE (-1125 2250);
FORCEPROP 1 LAST BODY_TYPE PLUMBING
J 0
(-1170 2207);
DISPLAY 0.340426 (-1170 2207);
PAINT GREEN (-1170 2207);
DISPLAY INVISIBLE (-1170 2207);
FORCEPROP 1 LAST PATH I263
J 0
(-1075 2275);
DISPLAY 0.872340 (-1075 2275);
PAINT AQUA (-1075 2275);
DISPLAY INVISIBLE (-1075 2275);
FORCEPROP 2 LAST ROOM DDR4_CH_A
J 0
(-1125 2350);
DISPLAY 0.787234 (-1125 2350);
PAINT ORANGE (-1125 2350);
DISPLAY INVISIBLE (-1125 2350);
FORCEPROP 1 LAST HDL_POWER PVDDQ_ABC
J 1
(-1125 2300);
DISPLAY 0.872340 (-1125 2300);
PAINT GREEN (-1125 2300);
DISPLAY INVISIBLE (-1125 2300);
FORCEADD GND..1
R 2
(1050 1150);
FORCEPROP 3 LASTPIN (1050 1200) SIG_NAME GND\g
J 0
(1060 1210);
DISPLAY 0.659574 (1060 1210);
PAINT MONO (1060 1210);
DISPLAY INVISIBLE (1060 1210);
FORCEPROP 1 LAST VOLTAGE 0
J 0
(1050 1150);
PAINT SKYBLUE (1050 1150);
DISPLAY INVISIBLE (1050 1150);
FORCEPROP 1 LAST SIZE 1B
J 2
(975 1100);
DISPLAY 1.170213 (975 1100);
PAINT GREEN (975 1100);
DISPLAY INVISIBLE (975 1100);
FORCEPROP 2 LAST CDS_LIB mstr_symbols
J 0
(1050 1150);
DISPLAY 0.787234 (1050 1150);
PAINT MONO (1050 1150);
DISPLAY INVISIBLE (1050 1150);
FORCEPROP 2 LAST BOM_COST MEM
J 0
(1050 1155);
PAINT ORANGE (1050 1155);
DISPLAY INVISIBLE (1050 1155);
FORCEPROP 1 LAST BODY_TYPE PLUMBING
J 2
(1095 1107);
DISPLAY 0.340426 (1095 1107);
PAINT GREEN (1095 1107);
DISPLAY INVISIBLE (1095 1107);
FORCEPROP 1 LAST PATH I264
J 2
(975 1150);
DISPLAY 1.404255 (975 1150);
PAINT GREEN (975 1150);
DISPLAY INVISIBLE (975 1150);
FORCEPROP 2 LAST ROOM DDR4_CH_A
J 0
(1050 1155);
PAINT ORANGE (1050 1155);
DISPLAY INVISIBLE (1050 1155);
FORCEPROP 1 LAST HDL_POWER GND
J 2
(1050 1300);
DISPLAY 0.553191 (1050 1300);
PAINT GREEN (1050 1300);
DISPLAY INVISIBLE (1050 1300);
FORCEADD GND..1
R 2
(2450 1150);
FORCEPROP 3 LASTPIN (2450 1200) SIG_NAME GND\g
J 0
(2460 1210);
DISPLAY 0.659574 (2460 1210);
PAINT MONO (2460 1210);
DISPLAY INVISIBLE (2460 1210);
FORCEPROP 1 LAST VOLTAGE 0
J 0
(2450 1150);
PAINT SKYBLUE (2450 1150);
DISPLAY INVISIBLE (2450 1150);
FORCEPROP 2 LAST CDS_LIB mstr_symbols
J 0
(2450 1150);
DISPLAY 0.787234 (2450 1150);
PAINT MONO (2450 1150);
DISPLAY INVISIBLE (2450 1150);
FORCEPROP 2 LAST BOM_COST MEM
J 0
(2450 1155);
PAINT ORANGE (2450 1155);
DISPLAY INVISIBLE (2450 1155);
FORCEPROP 1 LAST SIZE 1B
J 2
(2375 1100);
DISPLAY 1.170213 (2375 1100);
PAINT GREEN (2375 1100);
DISPLAY INVISIBLE (2375 1100);
FORCEPROP 1 LAST BODY_TYPE PLUMBING
J 2
(2495 1107);
DISPLAY 0.340426 (2495 1107);
PAINT GREEN (2495 1107);
DISPLAY INVISIBLE (2495 1107);
FORCEPROP 1 LAST PATH I265
J 2
(2375 1150);
DISPLAY 1.404255 (2375 1150);
PAINT GREEN (2375 1150);
DISPLAY INVISIBLE (2375 1150);
FORCEPROP 2 LAST ROOM DDR4_CH_A
J 0
(2450 1155);
PAINT ORANGE (2450 1155);
DISPLAY INVISIBLE (2450 1155);
FORCEPROP 1 LAST HDL_POWER GND
J 2
(2450 1300);
DISPLAY 0.553191 (2450 1300);
PAINT GREEN (2450 1300);
DISPLAY INVISIBLE (2450 1300);
FORCEADD GND..1
R 2
(-5050 1400);
FORCEPROP 3 LASTPIN (-5050 1450) SIG_NAME GND\g
J 0
(-5040 1460);
DISPLAY 0.659574 (-5040 1460);
PAINT MONO (-5040 1460);
DISPLAY INVISIBLE (-5040 1460);
FORCEPROP 1 LAST VOLTAGE 0
J 0
(-5050 1400);
PAINT SKYBLUE (-5050 1400);
DISPLAY INVISIBLE (-5050 1400);
FORCEPROP 2 LAST BOM_COST MEM
J 0
(-5050 1405);
PAINT ORANGE (-5050 1405);
DISPLAY INVISIBLE (-5050 1405);
FORCEPROP 2 LAST CDS_LIB mstr_symbols
J 0
(-5050 1400);
DISPLAY 0.787234 (-5050 1400);
PAINT MONO (-5050 1400);
DISPLAY INVISIBLE (-5050 1400);
FORCEPROP 1 LAST SIZE 1B
J 2
(-5125 1350);
DISPLAY 1.170213 (-5125 1350);
PAINT GREEN (-5125 1350);
DISPLAY INVISIBLE (-5125 1350);
FORCEPROP 1 LAST BODY_TYPE PLUMBING
J 2
(-5005 1357);
DISPLAY 0.340426 (-5005 1357);
PAINT GREEN (-5005 1357);
DISPLAY INVISIBLE (-5005 1357);
FORCEPROP 1 LAST PATH I267
J 2
(-5125 1400);
DISPLAY 1.404255 (-5125 1400);
PAINT GREEN (-5125 1400);
DISPLAY INVISIBLE (-5125 1400);
FORCEPROP 2 LAST ROOM DDR4_CH_A
J 0
(-5050 1405);
PAINT ORANGE (-5050 1405);
DISPLAY INVISIBLE (-5050 1405);
FORCEPROP 1 LAST HDL_POWER GND
J 2
(-5050 1550);
DISPLAY 0.553191 (-5050 1550);
PAINT GREEN (-5050 1550);
DISPLAY INVISIBLE (-5050 1550);
FORCEADD OFFPAGE..1
(-3800 2300);
FORCEPROP 2 LAST $XR0 21 
J 0
(-4021 2300);
DISPLAY 0.638298 (-4021 2300);
PAINT MONO (-4021 2300);
FORCEPROP 2 LAST $XR1 44 
J 0
(-4111 2300);
DISPLAY 0.638298 (-4111 2300);
PAINT MONO (-4111 2300);
FORCEPROP 2 LAST $XR2 45 
J 0
(-4201 2300);
DISPLAY 0.638298 (-4201 2300);
PAINT MONO (-4201 2300);
FORCEPROP 2 LAST $XR3 46 
J 0
(-4291 2300);
DISPLAY 0.638298 (-4291 2300);
PAINT MONO (-4291 2300);
FORCEPROP 2 LAST $XR4 47 
J 0
(-4381 2300);
DISPLAY 0.638298 (-4381 2300);
PAINT MONO (-4381 2300);
FORCEPROP 2 LAST $XR5 48 
J 0
(-4471 2300);
DISPLAY 0.638298 (-4471 2300);
PAINT MONO (-4471 2300);
FORCEPROP 2 LAST CDS_LIB mstr_standard
J 0
(-3800 2300);
DISPLAY 0.787234 (-3800 2300);
PAINT MONO (-3800 2300);
DISPLAY INVISIBLE (-3800 2300);
FORCEPROP 1 LAST OFFPAGE TRUE
J 0
(-3475 2175);
DISPLAY 0.936170 (-3475 2175);
PAINT GREEN (-3475 2175);
DISPLAY INVISIBLE (-3475 2175);
FORCEPROP 1 LAST COMMENT_BODY TRUE
J 0
(-3675 2200);
DISPLAY 0.936170 (-3675 2200);
PAINT GREEN (-3675 2200);
DISPLAY INVISIBLE (-3675 2200);
FORCEPROP 2 LAST PATH I269
J 0
(-4050 2350);
PAINT ORANGE (-4050 2350);
DISPLAY INVISIBLE (-4050 2350);
FORCEADD TAP..6
(-3150 4150);
FORCEPROP 3 LASTPIN (-3100 4150) SIG_NAME M_A_MA<12>
J 0
(-3090 4160);
DISPLAY 0.659574 (-3090 4160);
PAINT MONO (-3090 4160);
DISPLAY INVISIBLE (-3090 4160);
FORCEPROP 1 LASTPIN (-3100 4150) BN 12
J 0
(-3150 4160);
DISPLAY 0.617021 (-3150 4160);
PAINT PINK (-3150 4160);
FORCEPROP 2 LAST CDS_LIB mstr_standard
J 2
(-3150 4150);
DISPLAY 0.787234 (-3150 4150);
PAINT MONO (-3150 4150);
DISPLAY INVISIBLE (-3150 4150);
FORCEPROP 1 LAST BODY_TYPE PLUMBING
J 0
(-3150 4100);
DISPLAY 1.234043 (-3150 4100);
PAINT GREEN (-3150 4100);
DISPLAY INVISIBLE (-3150 4100);
FORCEPROP 1 LAST HDL_TAP TRUE
J 0
(-2825 4025);
DISPLAY 1.234043 (-2825 4025);
PAINT GREEN (-2825 4025);
DISPLAY INVISIBLE (-2825 4025);
FORCEPROP 1 LAST PATH I27
J 0
(-3150 4150);
DISPLAY 0.936170 (-3150 4150);
PAINT GREEN (-3150 4150);
DISPLAY INVISIBLE (-3150 4150);
FORCEADD OFFPAGE..5
(-4025 2050);
FORCEPROP 2 LAST $XR0 44 
J 0
(-4249 2050);
DISPLAY 0.638298 (-4249 2050);
PAINT MONO (-4249 2050);
FORCEPROP 2 LAST $XR1 45 
J 0
(-4339 2050);
DISPLAY 0.638298 (-4339 2050);
PAINT MONO (-4339 2050);
FORCEPROP 2 LAST $XR2 46 
J 0
(-4429 2050);
DISPLAY 0.638298 (-4429 2050);
PAINT MONO (-4429 2050);
FORCEPROP 2 LAST $XR3 47 
J 0
(-4519 2050);
DISPLAY 0.638298 (-4519 2050);
PAINT MONO (-4519 2050);
FORCEPROP 2 LAST $XR4 48 
J 0
(-4609 2050);
DISPLAY 0.638298 (-4609 2050);
PAINT MONO (-4609 2050);
FORCEPROP 2 LAST $XR5 49 
J 0
(-4699 2050);
DISPLAY 0.638298 (-4699 2050);
PAINT MONO (-4699 2050);
FORCEPROP 2 LAST $XR6 50 
J 0
(-4789 2050);
DISPLAY 0.638298 (-4789 2050);
PAINT MONO (-4789 2050);
FORCEPROP 2 LAST $XR7 51 
J 0
(-4879 2050);
DISPLAY 0.638298 (-4879 2050);
PAINT MONO (-4879 2050);
FORCEPROP 2 LAST $XR8 52 
J 0
(-4969 2050);
DISPLAY 0.638298 (-4969 2050);
PAINT MONO (-4969 2050);
FORCEPROP 2 LAST $XR9 53 
J 0
(-5059 2050);
DISPLAY 0.638298 (-5059 2050);
PAINT MONO (-5059 2050);
FORCEPROP 2 LAST $XR10 54 
J 0
(-4249 2014);
DISPLAY 0.638298 (-4249 2014);
PAINT MONO (-4249 2014);
FORCEPROP 2 LAST $XR11 77 
J 0
(-4339 2014);
DISPLAY 0.638298 (-4339 2014);
PAINT MONO (-4339 2014);
FORCEPROP 2 LAST $XR12 78 
J 0
(-4429 2014);
DISPLAY 0.638298 (-4429 2014);
PAINT MONO (-4429 2014);
FORCEPROP 2 LAST $XR13 79 
J 0
(-4519 2014);
DISPLAY 0.638298 (-4519 2014);
PAINT MONO (-4519 2014);
FORCEPROP 2 LAST $XR14 80 
J 0
(-4609 2014);
DISPLAY 0.638298 (-4609 2014);
PAINT MONO (-4609 2014);
FORCEPROP 2 LAST $XR15 81 
J 0
(-4699 2014);
DISPLAY 0.638298 (-4699 2014);
PAINT MONO (-4699 2014);
FORCEPROP 2 LAST $XR16 82 
J 0
(-4789 2014);
DISPLAY 0.638298 (-4789 2014);
PAINT MONO (-4789 2014);
FORCEPROP 2 LAST $XR17 83 
J 0
(-4879 2014);
DISPLAY 0.638298 (-4879 2014);
PAINT MONO (-4879 2014);
FORCEPROP 2 LAST $XR18 84 
J 0
(-4969 2014);
DISPLAY 0.638298 (-4969 2014);
PAINT MONO (-4969 2014);
FORCEPROP 2 LAST $XR19 85 
J 0
(-5059 2014);
DISPLAY 0.638298 (-5059 2014);
PAINT MONO (-5059 2014);
FORCEPROP 2 LAST $XR20 86 
J 0
(-4249 2086);
DISPLAY 0.638298 (-4249 2086);
PAINT MONO (-4249 2086);
FORCEPROP 2 LAST $XR21 87 
J 0
(-4339 2086);
DISPLAY 0.638298 (-4339 2086);
PAINT MONO (-4339 2086);
FORCEPROP 2 LAST $XR22 88 
J 0
(-4429 2086);
DISPLAY 0.638298 (-4429 2086);
PAINT MONO (-4429 2086);
FORCEPROP 2 LAST $XR23 94 
J 0
(-4519 2086);
DISPLAY 0.638298 (-4519 2086);
PAINT MONO (-4519 2086);
FORCEPROP 2 LAST CDS_LIB mstr_standard
J 0
(-4025 2050);
DISPLAY 0.787234 (-4025 2050);
PAINT MONO (-4025 2050);
DISPLAY INVISIBLE (-4025 2050);
FORCEPROP 1 LAST OFFPAGE TRUE
J 0
(-3700 1925);
DISPLAY 1.404255 (-3700 1925);
PAINT GREEN (-3700 1925);
DISPLAY INVISIBLE (-3700 1925);
FORCEPROP 1 LAST COMMENT_BODY TRUE
J 0
(-3925 1975);
DISPLAY 1.404255 (-3925 1975);
PAINT GREEN (-3925 1975);
DISPLAY INVISIBLE (-3925 1975);
FORCEPROP 2 LAST PATH I270
J 0
(-4300 2100);
PAINT ORANGE (-4300 2100);
DISPLAY INVISIBLE (-4300 2100);
FORCEADD GND..1
(-4350 800);
FORCEPROP 3 LASTPIN (-4350 850) SIG_NAME GND\g
J 0
(-4340 860);
DISPLAY 0.659574 (-4340 860);
PAINT MONO (-4340 860);
DISPLAY INVISIBLE (-4340 860);
FORCEPROP 1 LAST VOLTAGE 0
J 0
(-4350 800);
PAINT SKYBLUE (-4350 800);
DISPLAY INVISIBLE (-4350 800);
FORCEPROP 1 LAST SIZE 1B
J 0
(-4275 750);
DISPLAY 1.787234 (-4275 750);
PAINT GREEN (-4275 750);
DISPLAY INVISIBLE (-4275 750);
FORCEPROP 2 LAST CDS_LIB mstr_symbols
J 0
(-4350 800);
PAINT ORANGE (-4350 800);
DISPLAY INVISIBLE (-4350 800);
FORCEPROP 2 LAST BOM_COST MEM
J 0
(-4350 805);
PAINT ORANGE (-4350 805);
DISPLAY INVISIBLE (-4350 805);
FORCEPROP 1 LAST BODY_TYPE PLUMBING
J 0
(-4395 757);
DISPLAY 0.340426 (-4395 757);
PAINT GREEN (-4395 757);
DISPLAY INVISIBLE (-4395 757);
FORCEPROP 1 LAST PATH I271
J 0
(-4275 800);
DISPLAY 1.404255 (-4275 800);
PAINT GREEN (-4275 800);
DISPLAY INVISIBLE (-4275 800);
FORCEPROP 2 LAST ROOM DDR4_CH_A
J 0
(-4350 805);
PAINT ORANGE (-4350 805);
DISPLAY INVISIBLE (-4350 805);
FORCEPROP 1 LAST HDL_POWER GND
J 0
(-4350 950);
DISPLAY 1.404255 (-4350 950);
PAINT GREEN (-4350 950);
DISPLAY INVISIBLE (-4350 950);
FORCEADD CAP_A..1
R 2
(-4350 1050);
FORCEPROP 1 LAST LOCATION C4F10
J 2
(-4400 1150);
DISPLAY 0.617021 (-4400 1150);
PAINT AQUA (-4400 1150);
FORCEPROP 1 LAST PART_NUMBER A36096-045
J 2
(-4400 900);
DISPLAY 0.617021 (-4400 900);
PAINT BLUE (-4400 900);
FORCEPROP 1 LAST VALUE 0.01UF
J 2
(-4400 1100);
DISPLAY 0.617021 (-4400 1100);
PAINT SKYBLUE (-4400 1100);
FORCEPROP 1 LAST TOLERANCE 10%
J 2
(-4400 1000);
DISPLAY 0.617021 (-4400 1000);
PAINT SKYBLUE (-4400 1000);
FORCEPROP 1 LAST PACK_TYPE 0402V
J 2
(-4400 850);
DISPLAY 0.617021 (-4400 850);
PAINT SKYBLUE (-4400 850);
FORCEPROP 1 LAST VOLTAGE 25V
J 2
(-4400 1050);
DISPLAY 0.617021 (-4400 1050);
PAINT SKYBLUE (-4400 1050);
FORCEPROP 1 LAST MATERIAL X7R
J 2
(-4400 950);
DISPLAY 0.617021 (-4400 950);
PAINT SKYBLUE (-4400 950);
FORCEPROP 2 LAST CDS_LOCATION C4F10
J 2
(-4400 1150);
DISPLAY 0.617021 (-4400 1150);
PAINT AQUA (-4400 1150);
DISPLAY INVISIBLE (-4400 1150);
FORCEPROP 2 LAST BOM_COST MEM
J 0
(-4350 1050);
PAINT ORANGE (-4350 1050);
DISPLAY INVISIBLE (-4350 1050);
FORCEPROP 2 LAST CDS_LIB dev_discrete
J 0
(-4350 1050);
PAINT ORANGE (-4350 1050);
DISPLAY INVISIBLE (-4350 1050);
FORCEPROP 2 LAST CDS_SEC 1
J 2
(-4400 1250);
PAINT MONO (-4400 1250);
DISPLAY INVISIBLE (-4400 1250);
FORCEPROP 2 LAST $SEC 1
J 0
(-4400 1250);
PAINT MONO (-4400 1250);
DISPLAY INVISIBLE (-4400 1250);
FORCEPROP 1 LAST PATH I272
J 2
(-4400 1200);
DISPLAY 0.978723 (-4400 1200);
PAINT WHITE (-4400 1200);
DISPLAY INVISIBLE (-4400 1200);
FORCEPROP 2 LAST ROOM DDR4_CH_A
J 0
(-4350 1050);
PAINT ORANGE (-4350 1050);
DISPLAY INVISIBLE (-4350 1050);
FORCEPROP 1 LASTPIN (-4350 1150) $PN 1
J 2
(-4360 1130);
DISPLAY 0.787234 (-4360 1130);
PAINT ORANGE (-4360 1130);
DISPLAY INVISIBLE (-4360 1130);
FORCEPROP 1 LASTPIN (-4350 950) $PN 2
J 2
(-4360 930);
DISPLAY 0.787234 (-4360 930);
PAINT ORANGE (-4360 930);
DISPLAY INVISIBLE (-4360 930);
FORCEADD PVPP_ABC..1
(-750 2700);
FORCEPROP 3 LASTPIN (-750 2650) SIG_NAME PVPP_ABC\g
J 0
(-740 2660);
DISPLAY 0.659574 (-740 2660);
PAINT MONO (-740 2660);
DISPLAY INVISIBLE (-740 2660);
FORCEPROP 1 LAST VOLTAGE 2.5V
J 0
(-795 2657);
DISPLAY 0.340426 (-795 2657);
PAINT SKYBLUE (-795 2657);
DISPLAY INVISIBLE (-795 2657);
FORCEPROP 0 LAST BOM_COST MEM
J 0
(-750 2800);
PAINT ORANGE (-750 2800);
DISPLAY INVISIBLE (-750 2800);
FORCEPROP 2 LAST CDS_LIB mstr_symbols
J 0
(-750 2700);
PAINT ORANGE (-750 2700);
DISPLAY INVISIBLE (-750 2700);
FORCEPROP 1 LAST BODY_TYPE PLUMBING
J 0
(-795 2657);
DISPLAY 0.340426 (-795 2657);
PAINT GREEN (-795 2657);
DISPLAY INVISIBLE (-795 2657);
FORCEPROP 1 LAST PATH I273
J 0
(-700 2725);
DISPLAY 0.872340 (-700 2725);
PAINT AQUA (-700 2725);
DISPLAY INVISIBLE (-700 2725);
FORCEPROP 2 LAST ROOM DDR4_CH_A
J 0
(-750 2800);
PAINT ORANGE (-750 2800);
DISPLAY INVISIBLE (-750 2800);
FORCEPROP 1 LAST HDL_POWER PVPP_ABC
J 1
(-750 2750);
DISPLAY 0.872340 (-750 2750);
PAINT GREEN (-750 2750);
DISPLAY INVISIBLE (-750 2750);
FORCEADD PVPP_ABC..1
(-5050 1750);
FORCEPROP 3 LASTPIN (-5050 1700) SIG_NAME PVPP_ABC\g
J 0
(-5040 1710);
DISPLAY 0.659574 (-5040 1710);
PAINT MONO (-5040 1710);
DISPLAY INVISIBLE (-5040 1710);
FORCEPROP 1 LAST VOLTAGE 2.5V
J 0
(-5095 1707);
DISPLAY 0.340426 (-5095 1707);
PAINT SKYBLUE (-5095 1707);
DISPLAY INVISIBLE (-5095 1707);
FORCEPROP 0 LAST BOM_COST MEM
J 0
(-5050 1850);
PAINT ORANGE (-5050 1850);
DISPLAY INVISIBLE (-5050 1850);
FORCEPROP 2 LAST CDS_LIB mstr_symbols
J 0
(-5050 1750);
PAINT ORANGE (-5050 1750);
DISPLAY INVISIBLE (-5050 1750);
FORCEPROP 1 LAST BODY_TYPE PLUMBING
J 0
(-5095 1707);
DISPLAY 0.340426 (-5095 1707);
PAINT GREEN (-5095 1707);
DISPLAY INVISIBLE (-5095 1707);
FORCEPROP 1 LAST PATH I274
J 0
(-5000 1775);
DISPLAY 0.872340 (-5000 1775);
PAINT AQUA (-5000 1775);
DISPLAY INVISIBLE (-5000 1775);
FORCEPROP 2 LAST ROOM DDR4_CH_A
J 0
(-5050 1850);
PAINT ORANGE (-5050 1850);
DISPLAY INVISIBLE (-5050 1850);
FORCEPROP 1 LAST HDL_POWER PVPP_ABC
J 1
(-5050 1800);
DISPLAY 0.872340 (-5050 1800);
PAINT GREEN (-5050 1800);
DISPLAY INVISIBLE (-5050 1800);
FORCEADD PVTT_ABC..1
(-900 2400);
FORCEPROP 3 LASTPIN (-900 2350) SIG_NAME PVTT_ABC\g
J 0
(-890 2360);
DISPLAY 0.659574 (-890 2360);
PAINT MONO (-890 2360);
DISPLAY INVISIBLE (-890 2360);
FORCEPROP 1 LAST VOLTAGE 0.6V
J 0
(-945 2357);
DISPLAY 0.340426 (-945 2357);
PAINT SKYBLUE (-945 2357);
DISPLAY INVISIBLE (-945 2357);
FORCEPROP 2 LAST BOM_COST MEM
J 0
(-900 2405);
PAINT ORANGE (-900 2405);
DISPLAY INVISIBLE (-900 2405);
FORCEPROP 2 LAST CDS_LIB mstr_symbols
J 0
(-900 2400);
PAINT ORANGE (-900 2400);
DISPLAY INVISIBLE (-900 2400);
FORCEPROP 1 LAST BODY_TYPE PLUMBING
J 0
(-945 2357);
DISPLAY 0.340426 (-945 2357);
PAINT GREEN (-945 2357);
DISPLAY INVISIBLE (-945 2357);
FORCEPROP 1 LAST PATH I275
J 0
(-850 2425);
DISPLAY 0.872340 (-850 2425);
PAINT AQUA (-850 2425);
DISPLAY INVISIBLE (-850 2425);
FORCEPROP 2 LAST ROOM DDR4_CH_A
J 0
(-900 2405);
PAINT ORANGE (-900 2405);
DISPLAY INVISIBLE (-900 2405);
FORCEPROP 1 LAST HDL_POWER PVTT_ABC
J 1
(-900 2450);
DISPLAY 0.872340 (-900 2450);
PAINT GREEN (-900 2450);
DISPLAY INVISIBLE (-900 2450);
FORCEADD OFFPAGE..1
(-3800 950);
FORCEPROP 2 LAST $XR0 89 
J 0
(-4021 950);
DISPLAY 0.638298 (-4021 950);
PAINT MONO (-4021 950);
FORCEPROP 2 LAST $XR1 44 
J 0
(-4111 950);
DISPLAY 0.638298 (-4111 950);
PAINT MONO (-4111 950);
FORCEPROP 2 LAST $XR2 45 
J 0
(-4201 950);
DISPLAY 0.638298 (-4201 950);
PAINT MONO (-4201 950);
FORCEPROP 2 LAST $XR3 46 
J 0
(-4291 950);
DISPLAY 0.638298 (-4291 950);
PAINT MONO (-4291 950);
FORCEPROP 2 LAST $XR4 47 
J 0
(-4021 914);
DISPLAY 0.638298 (-4021 914);
PAINT MONO (-4021 914);
FORCEPROP 2 LAST $XR5 48 
J 0
(-4111 914);
DISPLAY 0.638298 (-4111 914);
PAINT MONO (-4111 914);
FORCEPROP 2 LAST CDS_LIB mstr_standard
J 0
(-3800 950);
PAINT ORANGE (-3800 950);
DISPLAY INVISIBLE (-3800 950);
FORCEPROP 1 LAST OFFPAGE TRUE
J 0
(-3475 825);
DISPLAY 0.936170 (-3475 825);
PAINT GREEN (-3475 825);
DISPLAY INVISIBLE (-3475 825);
FORCEPROP 1 LAST COMMENT_BODY TRUE
J 0
(-3675 850);
DISPLAY 0.936170 (-3675 850);
PAINT GREEN (-3675 850);
DISPLAY INVISIBLE (-3675 850);
FORCEPROP 2 LAST PATH I276
J 0
(-3750 1025);
PAINT ORANGE (-3750 1025);
DISPLAY INVISIBLE (-3750 1025);
FORCEADD TAP..6
(-3150 4100);
FORCEPROP 3 LASTPIN (-3100 4100) SIG_NAME M_A_MA<11>
J 0
(-3090 4110);
DISPLAY 0.659574 (-3090 4110);
PAINT MONO (-3090 4110);
DISPLAY INVISIBLE (-3090 4110);
FORCEPROP 1 LASTPIN (-3100 4100) BN 11
J 0
(-3150 4110);
DISPLAY 0.617021 (-3150 4110);
PAINT PINK (-3150 4110);
FORCEPROP 2 LAST CDS_LIB mstr_standard
J 2
(-3150 4100);
DISPLAY 0.787234 (-3150 4100);
PAINT MONO (-3150 4100);
DISPLAY INVISIBLE (-3150 4100);
FORCEPROP 1 LAST BODY_TYPE PLUMBING
J 0
(-3150 4050);
DISPLAY 1.234043 (-3150 4050);
PAINT GREEN (-3150 4050);
DISPLAY INVISIBLE (-3150 4050);
FORCEPROP 1 LAST HDL_TAP TRUE
J 0
(-2825 3975);
DISPLAY 1.234043 (-2825 3975);
PAINT GREEN (-2825 3975);
DISPLAY INVISIBLE (-2825 3975);
FORCEPROP 1 LAST PATH I28
J 0
(-3150 4100);
DISPLAY 0.936170 (-3150 4100);
PAINT GREEN (-3150 4100);
DISPLAY INVISIBLE (-3150 4100);
FORCEADD P12V_NVDIMM_ABC..1
(600 2775);
FORCEPROP 3 LASTPIN (600 2725) SIG_NAME P12V_NVDIMM_ABC\g
J 0
(610 2735);
DISPLAY 0.659574 (610 2735);
PAINT MONO (610 2735);
DISPLAY INVISIBLE (610 2735);
FORCEPROP 1 LAST VOLTAGE 12.0
J 0
(555 2732);
DISPLAY 0.340426 (555 2732);
PAINT SKYBLUE (555 2732);
DISPLAY INVISIBLE (555 2732);
FORCEPROP 2 LAST CDS_LIB mstr_symbols
J 0
(600 2775);
PAINT ORANGE (600 2775);
DISPLAY INVISIBLE (600 2775);
FORCEPROP 1 LAST BODY_TYPE PLUMBING
J 0
(555 2732);
DISPLAY 0.340426 (555 2732);
PAINT GREEN (555 2732);
DISPLAY INVISIBLE (555 2732);
FORCEPROP 1 LAST PATH I289
J 0
(650 2800);
DISPLAY 0.872340 (650 2800);
PAINT AQUA (650 2800);
DISPLAY INVISIBLE (650 2800);
FORCEPROP 1 LAST HDL_POWER P12V_NVDIMM_ABC
J 1
(600 2800);
DISPLAY 0.872340 (600 2800);
PAINT GREEN (600 2800);
DISPLAY INVISIBLE (600 2800);
FORCEADD TAP..6
(-3150 4050);
FORCEPROP 3 LASTPIN (-3100 4050) SIG_NAME M_A_MA<10>
J 0
(-3090 4060);
DISPLAY 0.659574 (-3090 4060);
PAINT MONO (-3090 4060);
DISPLAY INVISIBLE (-3090 4060);
FORCEPROP 1 LASTPIN (-3100 4050) BN 10
J 0
(-3150 4060);
DISPLAY 0.617021 (-3150 4060);
PAINT PINK (-3150 4060);
FORCEPROP 2 LAST CDS_LIB mstr_standard
J 2
(-3150 4050);
DISPLAY 0.787234 (-3150 4050);
PAINT MONO (-3150 4050);
DISPLAY INVISIBLE (-3150 4050);
FORCEPROP 1 LAST BODY_TYPE PLUMBING
J 0
(-3150 4000);
DISPLAY 1.234043 (-3150 4000);
PAINT GREEN (-3150 4000);
DISPLAY INVISIBLE (-3150 4000);
FORCEPROP 1 LAST HDL_TAP TRUE
J 0
(-2825 3925);
DISPLAY 1.234043 (-2825 3925);
PAINT GREEN (-2825 3925);
DISPLAY INVISIBLE (-2825 3925);
FORCEPROP 1 LAST PATH I29
J 0
(-3150 4050);
DISPLAY 0.936170 (-3150 4050);
PAINT GREEN (-3150 4050);
DISPLAY INVISIBLE (-3150 4050);
FORCEADD TAP..6
(-3150 4000);
FORCEPROP 3 LASTPIN (-3100 4000) SIG_NAME M_A_MA<9>
J 0
(-3090 4010);
DISPLAY 0.659574 (-3090 4010);
PAINT MONO (-3090 4010);
DISPLAY INVISIBLE (-3090 4010);
FORCEPROP 1 LASTPIN (-3100 4000) BN 9
J 0
(-3150 4010);
DISPLAY 0.617021 (-3150 4010);
PAINT PINK (-3150 4010);
FORCEPROP 2 LAST CDS_LIB mstr_standard
J 2
(-3150 4000);
DISPLAY 0.787234 (-3150 4000);
PAINT MONO (-3150 4000);
DISPLAY INVISIBLE (-3150 4000);
FORCEPROP 1 LAST BODY_TYPE PLUMBING
J 0
(-3150 3950);
DISPLAY 1.234043 (-3150 3950);
PAINT GREEN (-3150 3950);
DISPLAY INVISIBLE (-3150 3950);
FORCEPROP 1 LAST HDL_TAP TRUE
J 0
(-2825 3875);
DISPLAY 1.234043 (-2825 3875);
PAINT GREEN (-2825 3875);
DISPLAY INVISIBLE (-2825 3875);
FORCEPROP 1 LAST PATH I30
J 0
(-3150 4000);
DISPLAY 0.936170 (-3150 4000);
PAINT GREEN (-3150 4000);
DISPLAY INVISIBLE (-3150 4000);
FORCEADD TAP..6
(-3150 3950);
FORCEPROP 3 LASTPIN (-3100 3950) SIG_NAME M_A_MA<8>
J 0
(-3090 3960);
DISPLAY 0.659574 (-3090 3960);
PAINT MONO (-3090 3960);
DISPLAY INVISIBLE (-3090 3960);
FORCEPROP 1 LASTPIN (-3100 3950) BN 8
J 0
(-3150 3960);
DISPLAY 0.617021 (-3150 3960);
PAINT PINK (-3150 3960);
FORCEPROP 2 LAST CDS_LIB mstr_standard
J 2
(-3150 3950);
DISPLAY 0.787234 (-3150 3950);
PAINT MONO (-3150 3950);
DISPLAY INVISIBLE (-3150 3950);
FORCEPROP 1 LAST BODY_TYPE PLUMBING
J 0
(-3150 3900);
DISPLAY 1.234043 (-3150 3900);
PAINT GREEN (-3150 3900);
DISPLAY INVISIBLE (-3150 3900);
FORCEPROP 1 LAST HDL_TAP TRUE
J 0
(-2825 3825);
DISPLAY 1.234043 (-2825 3825);
PAINT GREEN (-2825 3825);
DISPLAY INVISIBLE (-2825 3825);
FORCEPROP 1 LAST PATH I31
J 0
(-3150 3950);
DISPLAY 0.936170 (-3150 3950);
PAINT GREEN (-3150 3950);
DISPLAY INVISIBLE (-3150 3950);
FORCEADD TAP..6
(-3150 3850);
FORCEPROP 3 LASTPIN (-3100 3850) SIG_NAME M_A_MA<6>
J 0
(-3090 3860);
DISPLAY 0.659574 (-3090 3860);
PAINT MONO (-3090 3860);
DISPLAY INVISIBLE (-3090 3860);
FORCEPROP 1 LASTPIN (-3100 3850) BN 6
J 0
(-3150 3860);
DISPLAY 0.617021 (-3150 3860);
PAINT PINK (-3150 3860);
FORCEPROP 2 LAST CDS_LIB mstr_standard
J 2
(-3150 3850);
DISPLAY 0.787234 (-3150 3850);
PAINT MONO (-3150 3850);
DISPLAY INVISIBLE (-3150 3850);
FORCEPROP 1 LAST BODY_TYPE PLUMBING
J 0
(-3150 3800);
DISPLAY 1.234043 (-3150 3800);
PAINT GREEN (-3150 3800);
DISPLAY INVISIBLE (-3150 3800);
FORCEPROP 1 LAST HDL_TAP TRUE
J 0
(-2825 3725);
DISPLAY 1.234043 (-2825 3725);
PAINT GREEN (-2825 3725);
DISPLAY INVISIBLE (-2825 3725);
FORCEPROP 1 LAST PATH I32
J 0
(-3150 3850);
DISPLAY 0.936170 (-3150 3850);
PAINT GREEN (-3150 3850);
DISPLAY INVISIBLE (-3150 3850);
FORCEADD TAP..6
(-3150 3900);
FORCEPROP 3 LASTPIN (-3100 3900) SIG_NAME M_A_MA<7>
J 0
(-3090 3910);
DISPLAY 0.659574 (-3090 3910);
PAINT MONO (-3090 3910);
DISPLAY INVISIBLE (-3090 3910);
FORCEPROP 1 LASTPIN (-3100 3900) BN 7
J 0
(-3150 3910);
DISPLAY 0.617021 (-3150 3910);
PAINT PINK (-3150 3910);
FORCEPROP 2 LAST CDS_LIB mstr_standard
J 2
(-3150 3900);
DISPLAY 0.787234 (-3150 3900);
PAINT MONO (-3150 3900);
DISPLAY INVISIBLE (-3150 3900);
FORCEPROP 1 LAST BODY_TYPE PLUMBING
J 0
(-3150 3850);
DISPLAY 1.234043 (-3150 3850);
PAINT GREEN (-3150 3850);
DISPLAY INVISIBLE (-3150 3850);
FORCEPROP 1 LAST HDL_TAP TRUE
J 0
(-2825 3775);
DISPLAY 1.234043 (-2825 3775);
PAINT GREEN (-2825 3775);
DISPLAY INVISIBLE (-2825 3775);
FORCEPROP 1 LAST PATH I33
J 0
(-3150 3900);
DISPLAY 0.936170 (-3150 3900);
PAINT GREEN (-3150 3900);
DISPLAY INVISIBLE (-3150 3900);
FORCEADD TAP..6
(-3150 3800);
FORCEPROP 3 LASTPIN (-3100 3800) SIG_NAME M_A_MA<5>
J 0
(-3090 3810);
DISPLAY 0.659574 (-3090 3810);
PAINT MONO (-3090 3810);
DISPLAY INVISIBLE (-3090 3810);
FORCEPROP 1 LASTPIN (-3100 3800) BN 5
J 0
(-3150 3810);
DISPLAY 0.617021 (-3150 3810);
PAINT PINK (-3150 3810);
FORCEPROP 2 LAST CDS_LIB mstr_standard
J 2
(-3150 3800);
DISPLAY 0.787234 (-3150 3800);
PAINT MONO (-3150 3800);
DISPLAY INVISIBLE (-3150 3800);
FORCEPROP 1 LAST BODY_TYPE PLUMBING
J 0
(-3150 3750);
DISPLAY 1.234043 (-3150 3750);
PAINT GREEN (-3150 3750);
DISPLAY INVISIBLE (-3150 3750);
FORCEPROP 1 LAST HDL_TAP TRUE
J 0
(-2825 3675);
DISPLAY 1.234043 (-2825 3675);
PAINT GREEN (-2825 3675);
DISPLAY INVISIBLE (-2825 3675);
FORCEPROP 1 LAST PATH I34
J 0
(-3150 3800);
DISPLAY 0.936170 (-3150 3800);
PAINT GREEN (-3150 3800);
DISPLAY INVISIBLE (-3150 3800);
FORCEADD TAP..6
(-3150 3700);
FORCEPROP 3 LASTPIN (-3100 3700) SIG_NAME M_A_MA<3>
J 0
(-3090 3710);
DISPLAY 0.659574 (-3090 3710);
PAINT MONO (-3090 3710);
DISPLAY INVISIBLE (-3090 3710);
FORCEPROP 1 LASTPIN (-3100 3700) BN 3
J 0
(-3150 3710);
DISPLAY 0.617021 (-3150 3710);
PAINT PINK (-3150 3710);
FORCEPROP 2 LAST CDS_LIB mstr_standard
J 2
(-3150 3700);
DISPLAY 0.787234 (-3150 3700);
PAINT MONO (-3150 3700);
DISPLAY INVISIBLE (-3150 3700);
FORCEPROP 1 LAST BODY_TYPE PLUMBING
J 0
(-3150 3650);
DISPLAY 1.234043 (-3150 3650);
PAINT GREEN (-3150 3650);
DISPLAY INVISIBLE (-3150 3650);
FORCEPROP 1 LAST HDL_TAP TRUE
J 0
(-2825 3575);
DISPLAY 1.234043 (-2825 3575);
PAINT GREEN (-2825 3575);
DISPLAY INVISIBLE (-2825 3575);
FORCEPROP 1 LAST PATH I35
J 0
(-3150 3700);
DISPLAY 0.936170 (-3150 3700);
PAINT GREEN (-3150 3700);
DISPLAY INVISIBLE (-3150 3700);
FORCEADD TAP..6
(-3150 3750);
FORCEPROP 3 LASTPIN (-3100 3750) SIG_NAME M_A_MA<4>
J 0
(-3090 3760);
DISPLAY 0.659574 (-3090 3760);
PAINT MONO (-3090 3760);
DISPLAY INVISIBLE (-3090 3760);
FORCEPROP 1 LASTPIN (-3100 3750) BN 4
J 0
(-3150 3760);
DISPLAY 0.617021 (-3150 3760);
PAINT PINK (-3150 3760);
FORCEPROP 2 LAST CDS_LIB mstr_standard
J 2
(-3150 3750);
DISPLAY 0.787234 (-3150 3750);
PAINT MONO (-3150 3750);
DISPLAY INVISIBLE (-3150 3750);
FORCEPROP 1 LAST BODY_TYPE PLUMBING
J 0
(-3150 3700);
DISPLAY 1.234043 (-3150 3700);
PAINT GREEN (-3150 3700);
DISPLAY INVISIBLE (-3150 3700);
FORCEPROP 1 LAST HDL_TAP TRUE
J 0
(-2825 3625);
DISPLAY 1.234043 (-2825 3625);
PAINT GREEN (-2825 3625);
DISPLAY INVISIBLE (-2825 3625);
FORCEPROP 1 LAST PATH I36
J 0
(-3150 3750);
DISPLAY 0.936170 (-3150 3750);
PAINT GREEN (-3150 3750);
DISPLAY INVISIBLE (-3150 3750);
FORCEADD TAP..6
(-3150 3650);
FORCEPROP 3 LASTPIN (-3100 3650) SIG_NAME M_A_MA<2>
J 0
(-3090 3660);
DISPLAY 0.659574 (-3090 3660);
PAINT MONO (-3090 3660);
DISPLAY INVISIBLE (-3090 3660);
FORCEPROP 1 LASTPIN (-3100 3650) BN 2
J 0
(-3150 3660);
DISPLAY 0.617021 (-3150 3660);
PAINT PINK (-3150 3660);
FORCEPROP 2 LAST CDS_LIB mstr_standard
J 2
(-3150 3650);
DISPLAY 0.787234 (-3150 3650);
PAINT MONO (-3150 3650);
DISPLAY INVISIBLE (-3150 3650);
FORCEPROP 1 LAST BODY_TYPE PLUMBING
J 0
(-3150 3600);
DISPLAY 1.234043 (-3150 3600);
PAINT GREEN (-3150 3600);
DISPLAY INVISIBLE (-3150 3600);
FORCEPROP 1 LAST HDL_TAP TRUE
J 0
(-2825 3525);
DISPLAY 1.234043 (-2825 3525);
PAINT GREEN (-2825 3525);
DISPLAY INVISIBLE (-2825 3525);
FORCEPROP 1 LAST PATH I37
J 0
(-3150 3650);
DISPLAY 0.936170 (-3150 3650);
PAINT GREEN (-3150 3650);
DISPLAY INVISIBLE (-3150 3650);
FORCEADD TAP..6
(-3150 3600);
FORCEPROP 3 LASTPIN (-3100 3600) SIG_NAME M_A_MA<1>
J 0
(-3090 3610);
DISPLAY 0.659574 (-3090 3610);
PAINT MONO (-3090 3610);
DISPLAY INVISIBLE (-3090 3610);
FORCEPROP 1 LASTPIN (-3100 3600) BN 1
J 0
(-3150 3610);
DISPLAY 0.617021 (-3150 3610);
PAINT PINK (-3150 3610);
FORCEPROP 2 LAST CDS_LIB mstr_standard
J 2
(-3150 3600);
DISPLAY 0.787234 (-3150 3600);
PAINT MONO (-3150 3600);
DISPLAY INVISIBLE (-3150 3600);
FORCEPROP 1 LAST BODY_TYPE PLUMBING
J 0
(-3150 3550);
DISPLAY 1.234043 (-3150 3550);
PAINT GREEN (-3150 3550);
DISPLAY INVISIBLE (-3150 3550);
FORCEPROP 1 LAST HDL_TAP TRUE
J 0
(-2825 3475);
DISPLAY 1.234043 (-2825 3475);
PAINT GREEN (-2825 3475);
DISPLAY INVISIBLE (-2825 3475);
FORCEPROP 1 LAST PATH I38
J 0
(-3150 3600);
DISPLAY 0.936170 (-3150 3600);
PAINT GREEN (-3150 3600);
DISPLAY INVISIBLE (-3150 3600);
FORCEADD TAP..6
(-3150 3550);
FORCEPROP 3 LASTPIN (-3100 3550) SIG_NAME M_A_MA<0>
J 0
(-3090 3560);
DISPLAY 0.659574 (-3090 3560);
PAINT MONO (-3090 3560);
DISPLAY INVISIBLE (-3090 3560);
FORCEPROP 1 LASTPIN (-3100 3550) BN 0
J 0
(-3150 3560);
DISPLAY 0.617021 (-3150 3560);
PAINT PINK (-3150 3560);
FORCEPROP 2 LAST CDS_LIB mstr_standard
J 2
(-3150 3550);
DISPLAY 0.787234 (-3150 3550);
PAINT MONO (-3150 3550);
DISPLAY INVISIBLE (-3150 3550);
FORCEPROP 1 LAST BODY_TYPE PLUMBING
J 0
(-3150 3500);
DISPLAY 1.234043 (-3150 3500);
PAINT GREEN (-3150 3500);
DISPLAY INVISIBLE (-3150 3500);
FORCEPROP 1 LAST HDL_TAP TRUE
J 0
(-2825 3425);
DISPLAY 1.234043 (-2825 3425);
PAINT GREEN (-2825 3425);
DISPLAY INVISIBLE (-2825 3425);
FORCEPROP 1 LAST PATH I39
J 0
(-3150 3550);
DISPLAY 0.936170 (-3150 3550);
PAINT GREEN (-3150 3550);
DISPLAY INVISIBLE (-3150 3550);
FORCEADD OFFPAGE..1
(-3800 4450);
FORCEPROP 2 LAST $XR0 23 
J 0
(-4021 4450);
DISPLAY 0.638298 (-4021 4450);
PAINT MONO (-4021 4450);
FORCEPROP 2 LAST $XR1 44 
J 0
(-4111 4450);
DISPLAY 0.638298 (-4111 4450);
PAINT MONO (-4111 4450);
FORCEPROP 2 LAST CDS_LIB mstr_standard
J 0
(-3800 4450);
DISPLAY 0.787234 (-3800 4450);
PAINT MONO (-3800 4450);
DISPLAY INVISIBLE (-3800 4450);
FORCEPROP 1 LAST OFFPAGE TRUE
J 0
(-3475 4325);
DISPLAY 0.936170 (-3475 4325);
PAINT GREEN (-3475 4325);
DISPLAY INVISIBLE (-3475 4325);
FORCEPROP 1 LAST COMMENT_BODY TRUE
J 0
(-3675 4350);
DISPLAY 0.936170 (-3675 4350);
PAINT GREEN (-3675 4350);
DISPLAY INVISIBLE (-3675 4350);
FORCEPROP 2 LAST PATH I40
J 0
(-3750 4525);
DISPLAY 0.787234 (-3750 4525);
PAINT MONO (-3750 4525);
DISPLAY INVISIBLE (-3750 4525);
FORCEADD OFFPAGE..1
(-3800 3400);
FORCEPROP 2 LAST $XR0 23 
J 0
(-4021 3400);
DISPLAY 0.638298 (-4021 3400);
PAINT MONO (-4021 3400);
FORCEPROP 2 LAST $XR1 44 
J 0
(-4111 3400);
DISPLAY 0.638298 (-4111 3400);
PAINT MONO (-4111 3400);
FORCEPROP 2 LAST CDS_LIB mstr_standard
J 0
(-3800 3400);
DISPLAY 0.787234 (-3800 3400);
PAINT MONO (-3800 3400);
DISPLAY INVISIBLE (-3800 3400);
FORCEPROP 1 LAST OFFPAGE TRUE
J 0
(-3475 3275);
DISPLAY 0.936170 (-3475 3275);
PAINT GREEN (-3475 3275);
DISPLAY INVISIBLE (-3475 3275);
FORCEPROP 1 LAST COMMENT_BODY TRUE
J 0
(-3675 3300);
DISPLAY 0.936170 (-3675 3300);
PAINT GREEN (-3675 3300);
DISPLAY INVISIBLE (-3675 3300);
FORCEPROP 2 LAST PATH I41
J 0
(-3750 3475);
DISPLAY 0.787234 (-3750 3475);
PAINT MONO (-3750 3475);
DISPLAY INVISIBLE (-3750 3475);
FORCEADD OFFPAGE..1
(-3800 3500);
FORCEPROP 2 LAST $XR0 23 
J 0
(-4021 3500);
DISPLAY 0.638298 (-4021 3500);
PAINT MONO (-4021 3500);
FORCEPROP 2 LAST $XR1 44 
J 0
(-4111 3500);
DISPLAY 0.638298 (-4111 3500);
PAINT MONO (-4111 3500);
FORCEPROP 2 LAST CDS_LIB mstr_standard
J 0
(-3800 3500);
DISPLAY 0.787234 (-3800 3500);
PAINT MONO (-3800 3500);
DISPLAY INVISIBLE (-3800 3500);
FORCEPROP 1 LAST OFFPAGE TRUE
J 0
(-3475 3375);
DISPLAY 0.936170 (-3475 3375);
PAINT GREEN (-3475 3375);
DISPLAY INVISIBLE (-3475 3375);
FORCEPROP 1 LAST COMMENT_BODY TRUE
J 0
(-3675 3400);
DISPLAY 0.936170 (-3675 3400);
PAINT GREEN (-3675 3400);
DISPLAY INVISIBLE (-3675 3400);
FORCEPROP 2 LAST PATH I42
J 0
(-3750 3575);
DISPLAY 0.787234 (-3750 3575);
PAINT MONO (-3750 3575);
DISPLAY INVISIBLE (-3750 3575);
FORCEADD TAP..6
(-3150 3300);
FORCEPROP 3 LASTPIN (-3100 3300) SIG_NAME M_A_BG<0>
J 0
(-3090 3310);
DISPLAY 0.659574 (-3090 3310);
PAINT MONO (-3090 3310);
DISPLAY INVISIBLE (-3090 3310);
FORCEPROP 1 LASTPIN (-3100 3300) BN 0
J 0
(-3150 3310);
DISPLAY 0.617021 (-3150 3310);
PAINT PINK (-3150 3310);
FORCEPROP 2 LAST CDS_LIB mstr_standard
J 0
(-3150 3300);
DISPLAY 0.787234 (-3150 3300);
PAINT MONO (-3150 3300);
DISPLAY INVISIBLE (-3150 3300);
FORCEPROP 1 LAST BODY_TYPE PLUMBING
J 0
(-3150 3250);
DISPLAY 1.234043 (-3150 3250);
PAINT GREEN (-3150 3250);
DISPLAY INVISIBLE (-3150 3250);
FORCEPROP 1 LAST HDL_TAP TRUE
J 0
(-2825 3175);
DISPLAY 1.234043 (-2825 3175);
PAINT GREEN (-2825 3175);
DISPLAY INVISIBLE (-2825 3175);
FORCEPROP 1 LAST PATH I43
J 0
(-3150 3300);
DISPLAY 0.936170 (-3150 3300);
PAINT GREEN (-3150 3300);
DISPLAY INVISIBLE (-3150 3300);
FORCEADD TAP..6
(-3150 3350);
FORCEPROP 3 LASTPIN (-3100 3350) SIG_NAME M_A_BG<1>
J 0
(-3090 3360);
DISPLAY 0.659574 (-3090 3360);
PAINT MONO (-3090 3360);
DISPLAY INVISIBLE (-3090 3360);
FORCEPROP 1 LASTPIN (-3100 3350) BN 1
J 0
(-3150 3360);
DISPLAY 0.617021 (-3150 3360);
PAINT PINK (-3150 3360);
FORCEPROP 2 LAST CDS_LIB mstr_standard
J 0
(-3150 3350);
DISPLAY 0.787234 (-3150 3350);
PAINT MONO (-3150 3350);
DISPLAY INVISIBLE (-3150 3350);
FORCEPROP 1 LAST BODY_TYPE PLUMBING
J 0
(-3150 3300);
DISPLAY 1.234043 (-3150 3300);
PAINT GREEN (-3150 3300);
DISPLAY INVISIBLE (-3150 3300);
FORCEPROP 1 LAST HDL_TAP TRUE
J 0
(-2825 3225);
DISPLAY 1.234043 (-2825 3225);
PAINT GREEN (-2825 3225);
DISPLAY INVISIBLE (-2825 3225);
FORCEPROP 1 LAST PATH I44
J 0
(-3150 3350);
DISPLAY 0.936170 (-3150 3350);
PAINT GREEN (-3150 3350);
DISPLAY INVISIBLE (-3150 3350);
FORCEADD TAP..6
(-3150 3450);
FORCEPROP 3 LASTPIN (-3100 3450) SIG_NAME M_A_BA<1>
J 0
(-3090 3460);
DISPLAY 0.659574 (-3090 3460);
PAINT MONO (-3090 3460);
DISPLAY INVISIBLE (-3090 3460);
FORCEPROP 1 LASTPIN (-3100 3450) BN 1
J 0
(-3150 3460);
DISPLAY 0.617021 (-3150 3460);
PAINT PINK (-3150 3460);
FORCEPROP 2 LAST CDS_LIB mstr_standard
J 0
(-3150 3450);
DISPLAY 0.787234 (-3150 3450);
PAINT MONO (-3150 3450);
DISPLAY INVISIBLE (-3150 3450);
FORCEPROP 1 LAST BODY_TYPE PLUMBING
J 0
(-3150 3400);
DISPLAY 1.234043 (-3150 3400);
PAINT GREEN (-3150 3400);
DISPLAY INVISIBLE (-3150 3400);
FORCEPROP 1 LAST HDL_TAP TRUE
J 0
(-2825 3325);
DISPLAY 1.234043 (-2825 3325);
PAINT GREEN (-2825 3325);
DISPLAY INVISIBLE (-2825 3325);
FORCEPROP 1 LAST PATH I45
J 0
(-3150 3450);
DISPLAY 0.936170 (-3150 3450);
PAINT GREEN (-3150 3450);
DISPLAY INVISIBLE (-3150 3450);
FORCEADD TAP..6
(-3150 3400);
FORCEPROP 3 LASTPIN (-3100 3400) SIG_NAME M_A_BA<0>
J 0
(-3090 3410);
DISPLAY 0.659574 (-3090 3410);
PAINT MONO (-3090 3410);
DISPLAY INVISIBLE (-3090 3410);
FORCEPROP 1 LASTPIN (-3100 3400) BN 0
J 0
(-3150 3410);
DISPLAY 0.617021 (-3150 3410);
PAINT PINK (-3150 3410);
FORCEPROP 2 LAST CDS_LIB mstr_standard
J 0
(-3150 3400);
DISPLAY 0.787234 (-3150 3400);
PAINT MONO (-3150 3400);
DISPLAY INVISIBLE (-3150 3400);
FORCEPROP 1 LAST BODY_TYPE PLUMBING
J 0
(-3150 3350);
DISPLAY 1.234043 (-3150 3350);
PAINT GREEN (-3150 3350);
DISPLAY INVISIBLE (-3150 3350);
FORCEPROP 1 LAST HDL_TAP TRUE
J 0
(-2825 3275);
DISPLAY 1.234043 (-2825 3275);
PAINT GREEN (-2825 3275);
DISPLAY INVISIBLE (-2825 3275);
FORCEPROP 1 LAST PATH I46
J 0
(-3150 3400);
DISPLAY 0.936170 (-3150 3400);
PAINT GREEN (-3150 3400);
DISPLAY INVISIBLE (-3150 3400);
FORCEADD OFFPAGE..1
(-3800 3000);
FORCEPROP 2 LAST $XR0 23 
J 0
(-4021 3000);
DISPLAY 0.638298 (-4021 3000);
PAINT MONO (-4021 3000);
FORCEPROP 2 LAST $XR1 44 
J 0
(-4111 3000);
DISPLAY 0.638298 (-4111 3000);
PAINT MONO (-4111 3000);
FORCEPROP 2 LAST CDS_LIB mstr_standard
J 0
(-3800 3000);
DISPLAY 0.787234 (-3800 3000);
PAINT MONO (-3800 3000);
DISPLAY INVISIBLE (-3800 3000);
FORCEPROP 1 LAST OFFPAGE TRUE
J 0
(-3475 2875);
DISPLAY 0.936170 (-3475 2875);
PAINT GREEN (-3475 2875);
DISPLAY INVISIBLE (-3475 2875);
FORCEPROP 1 LAST COMMENT_BODY TRUE
J 0
(-3675 2900);
DISPLAY 0.936170 (-3675 2900);
PAINT GREEN (-3675 2900);
DISPLAY INVISIBLE (-3675 2900);
FORCEPROP 2 LAST PATH I47
J 0
(-3750 3075);
DISPLAY 0.787234 (-3750 3075);
PAINT MONO (-3750 3075);
DISPLAY INVISIBLE (-3750 3075);
FORCEADD OFFPAGE..6
(-3800 2400);
FORCEPROP 2 LAST $XR0 23 
J 0
(-4049 2400);
DISPLAY 0.638298 (-4049 2400);
PAINT MONO (-4049 2400);
FORCEPROP 2 LAST $XR1 44 
J 0
(-4139 2400);
DISPLAY 0.638298 (-4139 2400);
PAINT MONO (-4139 2400);
FORCEPROP 2 LAST CDS_LIB mstr_standard
J 0
(-3800 2400);
DISPLAY 0.787234 (-3800 2400);
PAINT MONO (-3800 2400);
DISPLAY INVISIBLE (-3800 2400);
FORCEPROP 1 LAST OFFPAGE TRUE
J 0
(-3475 2275);
DISPLAY 0.936170 (-3475 2275);
PAINT GREEN (-3475 2275);
DISPLAY INVISIBLE (-3475 2275);
FORCEPROP 1 LAST COMMENT_BODY TRUE
J 0
(-3700 2325);
DISPLAY 0.936170 (-3700 2325);
PAINT GREEN (-3700 2325);
DISPLAY INVISIBLE (-3700 2325);
FORCEPROP 2 LAST PATH I48
J 0
(-3750 2475);
DISPLAY 0.787234 (-3750 2475);
PAINT MONO (-3750 2475);
DISPLAY INVISIBLE (-3750 2475);
FORCEADD TAP..6
(-3150 2350);
FORCEPROP 3 LASTPIN (-3100 2350) SIG_NAME M_A_ECC<6>
J 0
(-3090 2360);
DISPLAY 0.659574 (-3090 2360);
PAINT MONO (-3090 2360);
DISPLAY INVISIBLE (-3090 2360);
FORCEPROP 1 LASTPIN (-3100 2350) BN 6
J 0
(-3150 2360);
DISPLAY 0.617021 (-3150 2360);
PAINT PINK (-3150 2360);
FORCEPROP 2 LAST CDS_LIB mstr_standard
J 0
(-3150 2350);
DISPLAY 0.787234 (-3150 2350);
PAINT MONO (-3150 2350);
DISPLAY INVISIBLE (-3150 2350);
FORCEPROP 1 LAST BODY_TYPE PLUMBING
J 0
(-3150 2300);
DISPLAY 1.234043 (-3150 2300);
PAINT GREEN (-3150 2300);
DISPLAY INVISIBLE (-3150 2300);
FORCEPROP 1 LAST HDL_TAP TRUE
J 0
(-2825 2225);
DISPLAY 1.234043 (-2825 2225);
PAINT GREEN (-2825 2225);
DISPLAY INVISIBLE (-2825 2225);
FORCEPROP 1 LAST PATH I49
J 0
(-3150 2350);
DISPLAY 0.936170 (-3150 2350);
PAINT GREEN (-3150 2350);
DISPLAY INVISIBLE (-3150 2350);
FORCEADD TAP..6
(-3150 2300);
FORCEPROP 3 LASTPIN (-3100 2300) SIG_NAME M_A_ECC<7>
J 0
(-3090 2310);
DISPLAY 0.659574 (-3090 2310);
PAINT MONO (-3090 2310);
DISPLAY INVISIBLE (-3090 2310);
FORCEPROP 1 LASTPIN (-3100 2300) BN 7
J 0
(-3150 2310);
DISPLAY 0.617021 (-3150 2310);
PAINT PINK (-3150 2310);
FORCEPROP 2 LAST CDS_LIB mstr_standard
J 0
(-3150 2300);
DISPLAY 0.787234 (-3150 2300);
PAINT MONO (-3150 2300);
DISPLAY INVISIBLE (-3150 2300);
FORCEPROP 1 LAST BODY_TYPE PLUMBING
J 0
(-3150 2250);
DISPLAY 1.234043 (-3150 2250);
PAINT GREEN (-3150 2250);
DISPLAY INVISIBLE (-3150 2250);
FORCEPROP 1 LAST HDL_TAP TRUE
J 0
(-2825 2175);
DISPLAY 1.234043 (-2825 2175);
PAINT GREEN (-2825 2175);
DISPLAY INVISIBLE (-2825 2175);
FORCEPROP 1 LAST PATH I50
J 0
(-3150 2300);
DISPLAY 0.936170 (-3150 2300);
PAINT GREEN (-3150 2300);
DISPLAY INVISIBLE (-3150 2300);
FORCEADD TAP..6
(-3150 2250);
FORCEPROP 3 LASTPIN (-3100 2250) SIG_NAME M_A_ECC<4>
J 0
(-3090 2260);
DISPLAY 0.659574 (-3090 2260);
PAINT MONO (-3090 2260);
DISPLAY INVISIBLE (-3090 2260);
FORCEPROP 1 LASTPIN (-3100 2250) BN 4
J 0
(-3150 2260);
DISPLAY 0.617021 (-3150 2260);
PAINT PINK (-3150 2260);
FORCEPROP 2 LAST CDS_LIB mstr_standard
J 0
(-3150 2250);
DISPLAY 0.787234 (-3150 2250);
PAINT MONO (-3150 2250);
DISPLAY INVISIBLE (-3150 2250);
FORCEPROP 1 LAST BODY_TYPE PLUMBING
J 0
(-3150 2200);
DISPLAY 1.234043 (-3150 2200);
PAINT GREEN (-3150 2200);
DISPLAY INVISIBLE (-3150 2200);
FORCEPROP 1 LAST HDL_TAP TRUE
J 0
(-2825 2125);
DISPLAY 1.234043 (-2825 2125);
PAINT GREEN (-2825 2125);
DISPLAY INVISIBLE (-2825 2125);
FORCEPROP 1 LAST PATH I51
J 0
(-3150 2250);
DISPLAY 0.936170 (-3150 2250);
PAINT GREEN (-3150 2250);
DISPLAY INVISIBLE (-3150 2250);
FORCEADD TAP..6
(-3150 2200);
FORCEPROP 3 LASTPIN (-3100 2200) SIG_NAME M_A_ECC<5>
J 0
(-3090 2210);
DISPLAY 0.659574 (-3090 2210);
PAINT MONO (-3090 2210);
DISPLAY INVISIBLE (-3090 2210);
FORCEPROP 1 LASTPIN (-3100 2200) BN 5
J 0
(-3150 2210);
DISPLAY 0.617021 (-3150 2210);
PAINT PINK (-3150 2210);
FORCEPROP 2 LAST CDS_LIB mstr_standard
J 0
(-3150 2200);
DISPLAY 0.787234 (-3150 2200);
PAINT MONO (-3150 2200);
DISPLAY INVISIBLE (-3150 2200);
FORCEPROP 1 LAST BODY_TYPE PLUMBING
J 0
(-3150 2150);
DISPLAY 1.234043 (-3150 2150);
PAINT GREEN (-3150 2150);
DISPLAY INVISIBLE (-3150 2150);
FORCEPROP 1 LAST HDL_TAP TRUE
J 0
(-2825 2075);
DISPLAY 1.234043 (-2825 2075);
PAINT GREEN (-2825 2075);
DISPLAY INVISIBLE (-2825 2075);
FORCEPROP 1 LAST PATH I52
J 0
(-3150 2200);
DISPLAY 0.936170 (-3150 2200);
PAINT GREEN (-3150 2200);
DISPLAY INVISIBLE (-3150 2200);
FORCEADD TAP..6
(-3150 2150);
FORCEPROP 3 LASTPIN (-3100 2150) SIG_NAME M_A_ECC<2>
J 0
(-3090 2160);
DISPLAY 0.659574 (-3090 2160);
PAINT MONO (-3090 2160);
DISPLAY INVISIBLE (-3090 2160);
FORCEPROP 1 LASTPIN (-3100 2150) BN 2
J 0
(-3150 2160);
DISPLAY 0.617021 (-3150 2160);
PAINT PINK (-3150 2160);
FORCEPROP 2 LAST CDS_LIB mstr_standard
J 0
(-3150 2150);
DISPLAY 0.787234 (-3150 2150);
PAINT MONO (-3150 2150);
DISPLAY INVISIBLE (-3150 2150);
FORCEPROP 1 LAST BODY_TYPE PLUMBING
J 0
(-3150 2100);
DISPLAY 1.234043 (-3150 2100);
PAINT GREEN (-3150 2100);
DISPLAY INVISIBLE (-3150 2100);
FORCEPROP 1 LAST HDL_TAP TRUE
J 0
(-2825 2025);
DISPLAY 1.234043 (-2825 2025);
PAINT GREEN (-2825 2025);
DISPLAY INVISIBLE (-2825 2025);
FORCEPROP 1 LAST PATH I53
J 0
(-3150 2150);
DISPLAY 0.936170 (-3150 2150);
PAINT GREEN (-3150 2150);
DISPLAY INVISIBLE (-3150 2150);
FORCEADD TAP..6
(-3150 2050);
FORCEPROP 3 LASTPIN (-3100 2050) SIG_NAME M_A_ECC<0>
J 0
(-3090 2060);
DISPLAY 0.659574 (-3090 2060);
PAINT MONO (-3090 2060);
DISPLAY INVISIBLE (-3090 2060);
FORCEPROP 1 LASTPIN (-3100 2050) BN 0
J 0
(-3150 2060);
DISPLAY 0.617021 (-3150 2060);
PAINT PINK (-3150 2060);
FORCEPROP 2 LAST CDS_LIB mstr_standard
J 0
(-3150 2050);
DISPLAY 0.787234 (-3150 2050);
PAINT MONO (-3150 2050);
DISPLAY INVISIBLE (-3150 2050);
FORCEPROP 1 LAST BODY_TYPE PLUMBING
J 0
(-3150 2000);
DISPLAY 1.234043 (-3150 2000);
PAINT GREEN (-3150 2000);
DISPLAY INVISIBLE (-3150 2000);
FORCEPROP 1 LAST HDL_TAP TRUE
J 0
(-2825 1925);
DISPLAY 1.234043 (-2825 1925);
PAINT GREEN (-2825 1925);
DISPLAY INVISIBLE (-2825 1925);
FORCEPROP 1 LAST PATH I54
J 0
(-3150 2050);
DISPLAY 0.936170 (-3150 2050);
PAINT GREEN (-3150 2050);
DISPLAY INVISIBLE (-3150 2050);
FORCEADD TAP..6
(-3150 2100);
FORCEPROP 3 LASTPIN (-3100 2100) SIG_NAME M_A_ECC<3>
J 0
(-3090 2110);
DISPLAY 0.659574 (-3090 2110);
PAINT MONO (-3090 2110);
DISPLAY INVISIBLE (-3090 2110);
FORCEPROP 1 LASTPIN (-3100 2100) BN 3
J 0
(-3150 2110);
DISPLAY 0.617021 (-3150 2110);
PAINT PINK (-3150 2110);
FORCEPROP 2 LAST CDS_LIB mstr_standard
J 0
(-3150 2100);
DISPLAY 0.787234 (-3150 2100);
PAINT MONO (-3150 2100);
DISPLAY INVISIBLE (-3150 2100);
FORCEPROP 1 LAST BODY_TYPE PLUMBING
J 0
(-3150 2050);
DISPLAY 1.234043 (-3150 2050);
PAINT GREEN (-3150 2050);
DISPLAY INVISIBLE (-3150 2050);
FORCEPROP 1 LAST HDL_TAP TRUE
J 0
(-2825 1975);
DISPLAY 1.234043 (-2825 1975);
PAINT GREEN (-2825 1975);
DISPLAY INVISIBLE (-2825 1975);
FORCEPROP 1 LAST PATH I55
J 0
(-3150 2100);
DISPLAY 0.936170 (-3150 2100);
PAINT GREEN (-3150 2100);
DISPLAY INVISIBLE (-3150 2100);
FORCEADD TAP..6
(-3150 2000);
FORCEPROP 3 LASTPIN (-3100 2000) SIG_NAME M_A_ECC<1>
J 0
(-3090 2010);
DISPLAY 0.659574 (-3090 2010);
PAINT MONO (-3090 2010);
DISPLAY INVISIBLE (-3090 2010);
FORCEPROP 1 LASTPIN (-3100 2000) BN 1
J 0
(-3150 2010);
DISPLAY 0.617021 (-3150 2010);
PAINT PINK (-3150 2010);
FORCEPROP 2 LAST CDS_LIB mstr_standard
J 0
(-3150 2000);
DISPLAY 0.787234 (-3150 2000);
PAINT MONO (-3150 2000);
DISPLAY INVISIBLE (-3150 2000);
FORCEPROP 1 LAST BODY_TYPE PLUMBING
J 0
(-3150 1950);
DISPLAY 1.234043 (-3150 1950);
PAINT GREEN (-3150 1950);
DISPLAY INVISIBLE (-3150 1950);
FORCEPROP 1 LAST HDL_TAP TRUE
J 0
(-2825 1875);
DISPLAY 1.234043 (-2825 1875);
PAINT GREEN (-2825 1875);
DISPLAY INVISIBLE (-2825 1875);
FORCEPROP 1 LAST PATH I56
J 0
(-3150 2000);
DISPLAY 0.936170 (-3150 2000);
PAINT GREEN (-3150 2000);
DISPLAY INVISIBLE (-3150 2000);
FORCEADD OFFPAGE..1
(-3800 2350);
FORCEPROP 2 LAST $XR0 23 
J 0
(-4051 2350);
DISPLAY 0.638298 (-4051 2350);
PAINT MONO (-4051 2350);
FORCEPROP 2 LAST $XR1 44 
J 0
(-4141 2350);
DISPLAY 0.638298 (-4141 2350);
PAINT MONO (-4141 2350);
FORCEPROP 2 LAST CDS_LIB mstr_standard
J 0
(-3800 2350);
DISPLAY 0.787234 (-3800 2350);
PAINT MONO (-3800 2350);
DISPLAY INVISIBLE (-3800 2350);
FORCEPROP 1 LAST OFFPAGE TRUE
J 0
(-3475 2225);
DISPLAY 0.936170 (-3475 2225);
PAINT GREEN (-3475 2225);
DISPLAY INVISIBLE (-3475 2225);
FORCEPROP 1 LAST COMMENT_BODY TRUE
J 0
(-3675 2250);
DISPLAY 0.936170 (-3675 2250);
PAINT GREEN (-3675 2250);
DISPLAY INVISIBLE (-3675 2250);
FORCEPROP 2 LAST PATH I57
J 0
(-3750 2425);
DISPLAY 0.787234 (-3750 2425);
PAINT MONO (-3750 2425);
DISPLAY INVISIBLE (-3750 2425);
FORCEADD OFFPAGE..5
(-4025 1750);
FORCEPROP 2 LAST $XR0 44 
J 0
(-4249 1750);
DISPLAY 0.638298 (-4249 1750);
PAINT MONO (-4249 1750);
FORCEPROP 2 LAST $XR1 23 
J 0
(-4339 1750);
DISPLAY 0.638298 (-4339 1750);
PAINT MONO (-4339 1750);
FORCEPROP 2 LAST CDS_LIB mstr_standard
J 0
(-4025 1750);
DISPLAY 0.787234 (-4025 1750);
PAINT MONO (-4025 1750);
DISPLAY INVISIBLE (-4025 1750);
FORCEPROP 1 LAST OFFPAGE TRUE
J 0
(-3700 1625);
DISPLAY 1.404255 (-3700 1625);
PAINT GREEN (-3700 1625);
DISPLAY INVISIBLE (-3700 1625);
FORCEPROP 1 LAST COMMENT_BODY TRUE
J 0
(-3925 1675);
DISPLAY 1.404255 (-3925 1675);
PAINT GREEN (-3925 1675);
DISPLAY INVISIBLE (-3925 1675);
FORCEPROP 2 LAST PATH I59
J 0
(-3975 1825);
DISPLAY 0.787234 (-3975 1825);
PAINT MONO (-3975 1825);
DISPLAY INVISIBLE (-3975 1825);
FORCEADD OFFPAGE..1
(-4025 1700);
FORCEPROP 2 LAST $XR0 23 
J 0
(-4276 1700);
DISPLAY 0.638298 (-4276 1700);
PAINT MONO (-4276 1700);
FORCEPROP 2 LAST $XR1 44 
J 0
(-4366 1700);
DISPLAY 0.638298 (-4366 1700);
PAINT MONO (-4366 1700);
FORCEPROP 2 LAST CDS_LIB mstr_standard
J 0
(-4025 1700);
DISPLAY 0.787234 (-4025 1700);
PAINT MONO (-4025 1700);
DISPLAY INVISIBLE (-4025 1700);
FORCEPROP 1 LAST OFFPAGE TRUE
J 0
(-3700 1575);
DISPLAY 0.936170 (-3700 1575);
PAINT GREEN (-3700 1575);
DISPLAY INVISIBLE (-3700 1575);
FORCEPROP 1 LAST COMMENT_BODY TRUE
J 0
(-3900 1600);
DISPLAY 0.936170 (-3900 1600);
PAINT GREEN (-3900 1600);
DISPLAY INVISIBLE (-3900 1600);
FORCEPROP 2 LAST PATH I60
J 0
(-3975 1775);
DISPLAY 0.787234 (-3975 1775);
PAINT MONO (-3975 1775);
DISPLAY INVISIBLE (-3975 1775);
FORCEADD OFFPAGE..1
(-4500 1250);
FORCEPROP 2 LAST $XR0 98 
J 0
(-4721 1250);
DISPLAY 0.638298 (-4721 1250);
PAINT MONO (-4721 1250);
FORCEPROP 2 LAST $XR1 44 
J 0
(-4811 1250);
DISPLAY 0.638298 (-4811 1250);
PAINT MONO (-4811 1250);
FORCEPROP 2 LAST CDS_LIB mstr_standard
J 0
(-4500 1250);
DISPLAY 0.787234 (-4500 1250);
PAINT MONO (-4500 1250);
DISPLAY INVISIBLE (-4500 1250);
FORCEPROP 1 LAST OFFPAGE TRUE
J 0
(-4175 1125);
DISPLAY 0.936170 (-4175 1125);
PAINT GREEN (-4175 1125);
DISPLAY INVISIBLE (-4175 1125);
FORCEPROP 1 LAST COMMENT_BODY TRUE
J 0
(-4375 1150);
DISPLAY 0.936170 (-4375 1150);
PAINT GREEN (-4375 1150);
DISPLAY INVISIBLE (-4375 1150);
FORCEPROP 2 LAST PATH I61
J 0
(-4450 1325);
DISPLAY 0.787234 (-4450 1325);
PAINT MONO (-4450 1325);
DISPLAY INVISIBLE (-4450 1325);
FORCEADD BOM_NOTE..1
(-4975 4925);
FORCEPROP 0 LAST L1 STUFF FOR SKU A & B
J 0
(-5125 4825);
DISPLAY 1.063830 (-5125 4825);
PAINT WHITE (-5125 4825);
FORCEPROP 2 LAST BOM_COST SB
J 0
(-5125 4900);
DISPLAY 1.361702 (-5125 4900);
PAINT ORANGE (-5125 4900);
DISPLAY INVISIBLE (-5125 4900);
FORCEPROP 2 LAST CDS_LIB mstr_symbols
J 0
(-4975 4925);
PAINT ORANGE (-4975 4925);
DISPLAY INVISIBLE (-4975 4925);
FORCEPROP 1 LAST COMMENT_BODY TRUE
J 0
(-4950 5025);
DISPLAY 1.319149 (-4950 5025);
PAINT ORANGE (-4950 5025);
DISPLAY INVISIBLE (-4950 5025);
FORCEPROP 2 LAST ROOM SB_HEADERS
J 0
(-5125 4900);
DISPLAY 1.361702 (-5125 4900);
PAINT ORANGE (-5125 4900);
DISPLAY INVISIBLE (-5125 4900);
FORCEADD INTEL_CORP_BPAGE..1
(2625 225);
FORCEPROP 1 LAST CDS_CON_LAST_MODIFIED Tue Dec 01 11:51:26 2015
J 0
(1200 550);
DISPLAY 0.787234 (1200 550);
PAINT ORANGE (1200 550);
DISPLAY INVISIBLE (1200 550);
FORCEPROP 1 LAST CUSTOM_TXT_CDS <CURRENT_DESIGN_SHEET> OF <TOTAL_DESIGN_SHEETS>
J 0
(2125 250);
PAINT GREEN (2125 250);
FORCEPROP 2 LAST CUSTOM_TXT_CDS <XR_PAGE_TITLE>
J 0
(-5265 5475);
DISPLAY 0.638298 (-5265 5475);
PAINT PINK (-5265 5475);
DISPLAY INVISIBLE (-5265 5475);
FORCEPROP 2 LAST CUSTOM_TXT_CDS <CON_LAST_MODIFIED>
J 0
(700 575);
DISPLAY 1.063830 (700 575);
PAINT GREEN (700 575);
FORCEPROP 1 LAST SCH_ADDRESS3 Santa Clara, CA 95052-8119
J 0
(-1350 250);
DISPLAY 0.617021 (-1350 250);
PAINT GREEN (-1350 250);
FORCEPROP 1 LAST SCH_ADDRESS2 P.O. BOX 58119
J 0
(-1350 300);
DISPLAY 0.617021 (-1350 300);
PAINT GREEN (-1350 300);
FORCEPROP 1 LAST SCH_ADDRESS1 2200 Mission College Blvd.
J 0
(-1350 350);
DISPLAY 0.617021 (-1350 350);
PAINT GREEN (-1350 350);
FORCEPROP 1 LAST SCH_TITLE CPU0 DDR4 CH A DIMM0
J 0
(-5325 275);
DISPLAY 1.212766 (-5325 275);
PAINT WHITE (-5325 275);
FORCEPROP 1 LAST SCH_NUMBER H4694802
J 0
(1325 375);
DISPLAY 1.212766 (1325 375);
PAINT YELLOW (1325 375);
FORCEPROP 1 LAST SCH_DEPT BESD
J 1
(-1825 325);
DISPLAY 1.212766 (-1825 325);
PAINT YELLOW (-1825 325);
FORCEPROP 1 LAST SCH_REV 2.420
J 0
(2375 375);
DISPLAY 0.978723 (2375 375);
PAINT YELLOW (2375 375);
FORCEPROP 2 LAST PAGE_BORDER TRUE
J 0
(-5265 5475);
DISPLAY 0.680851 (-5265 5475);
PAINT PINK (-5265 5475);
DISPLAY INVISIBLE (-5265 5475);
FORCEPROP 2 LAST CDS_LIB mstr_symbols
J 0
(2625 225);
DISPLAY 0.787234 (2625 225);
PAINT MONO (2625 225);
DISPLAY INVISIBLE (2625 225);
FORCEPROP 1 LAST COMMENT_BODY TRUE
J 0
(2635 235);
DISPLAY 0.382979 (2635 235);
PAINT GREEN (2635 235);
DISPLAY INVISIBLE (2635 235);
FORCEPROP 2 LAST CDS_XR_PAGE_TITLE CR-43 : @BASEBOARD_FAB2_LIB.BASEBOARD_FAB2(SCH_1):PAGE43
J 0
(-5265 5475);
DISPLAY 0.638298 (-5265 5475);
PAINT PINK (-5265 5475);
DISPLAY INVISIBLE (-5265 5475);
WIRE 17 -1 (900 4075)(900 4175);
WIRE 17 -1 (900 3975)(900 4075);
WIRE 17 -1 (900 4175)(900 4275);
WIRE 17 -1 (900 4275)(900 4375);
WIRE 17 -1 (900 3875)(900 3975);
WIRE 17 -1 (900 3775)(900 3875);
WIRE 17 -1 (900 4375)(900 4475);
WIRE 17 -1 (900 4475)(900 4575);
WIRE 17 -1 (900 3675)(900 3775);
WIRE 17 -1 (900 3575)(900 3675);
WIRE 17 -1 (900 4575)(900 4675);
WIRE 17 -1 (900 4675)(900 4775);
WIRE 17 -1 (900 3475)(900 3575);
WIRE 17 -1 (900 3375)(900 3475);
WIRE 17 -1 (900 4775)(900 4875);
WIRE 17 -1 (900 4875)(900 4900);
WIRE 17 -1 (900 3275)(900 3375);
WIRE 17 -1 (900 3175)(900 3275);
WIRE 17 -1 (1500 4900)(900 4900);
FORCEPROP 2 LAST SIG_NAME M_A_DQS_DN<17:0>
J 0
(950 4910);
DISPLAY 0.617021 (950 4910);
PAINT ORANGE (950 4910);
WIRE 17 -1 (700 4125)(700 4225);
WIRE 17 -1 (700 4025)(700 4125);
WIRE 17 -1 (700 4225)(700 4325);
WIRE 17 -1 (700 4325)(700 4425);
WIRE 17 -1 (700 3925)(700 4025);
WIRE 17 -1 (700 3825)(700 3925);
WIRE 17 -1 (700 4425)(700 4525);
WIRE 17 -1 (700 4525)(700 4625);
WIRE 17 -1 (700 3725)(700 3825);
WIRE 17 -1 (700 3625)(700 3725);
WIRE 17 -1 (700 4625)(700 4725);
WIRE 17 -1 (700 4725)(700 4825);
WIRE 17 -1 (700 3525)(700 3625);
WIRE 17 -1 (700 3425)(700 3525);
WIRE 17 -1 (700 4825)(700 4925);
WIRE 17 -1 (700 4925)(700 4950);
WIRE 17 -1 (700 3325)(700 3425);
WIRE 17 -1 (700 3225)(700 3325);
WIRE 17 -1 (1500 4950)(700 4950);
FORCEPROP 2 LAST SIG_NAME M_A_DQS_DP<17:0>
J 0
(950 4960);
DISPLAY 0.617021 (950 4960);
PAINT ORANGE (950 4960);
WIRE 17 -1 (-1550 4225)(-1550 4275);
WIRE 17 -1 (-1550 4175)(-1550 4225);
WIRE 17 -1 (-1550 4275)(-1550 4325);
WIRE 17 -1 (-1550 4325)(-1550 4375);
WIRE 17 -1 (-1550 4125)(-1550 4175);
WIRE 17 -1 (-1550 4075)(-1550 4125);
WIRE 17 -1 (-1550 4375)(-1550 4425);
WIRE 17 -1 (-1550 4425)(-1550 4450);
WIRE 17 -1 (-1550 4025)(-1550 4075);
WIRE 17 -1 (-1550 3975)(-1550 4025);
WIRE 17 -1 (-1050 4450)(-1550 4450);
FORCEPROP 2 LAST SIG_NAME M_A_DQ<63:0>
J 0
(-1510 4460);
DISPLAY 0.617021 (-1510 4460);
PAINT ORANGE (-1510 4460);
WIRE 17 -1 (-1550 3925)(-1550 3975);
WIRE 17 -1 (-1550 3875)(-1550 3925);
WIRE 17 -1 (-1550 3825)(-1550 3875);
WIRE 17 -1 (-1550 3775)(-1550 3825);
WIRE 17 -1 (-3200 4175)(-3200 4225);
WIRE 17 -1 (-3200 4125)(-3200 4175);
WIRE 17 -1 (-3200 4225)(-3200 4275);
WIRE 17 -1 (-3200 4275)(-3200 4325);
WIRE 17 -1 (-3200 4075)(-3200 4125);
WIRE 17 -1 (-3200 4025)(-3200 4075);
WIRE 17 -1 (-3200 4325)(-3200 4375);
WIRE 17 -1 (-3200 4375)(-3200 4425);
WIRE 17 -1 (-3200 3975)(-3200 4025);
WIRE 17 -1 (-3200 3925)(-3200 3975);
WIRE 17 -1 (-3200 4425)(-3200 4450);
WIRE 17 -1 (-3750 4450)(-3200 4450);
FORCEPROP 2 LAST SIG_NAME M_A_MA<17:0>
J 0
(-3700 4460);
DISPLAY 0.617021 (-3700 4460);
PAINT ORANGE (-3700 4460);
WIRE 17 -1 (-3200 3875)(-3200 3925);
WIRE 17 -1 (-3200 3825)(-3200 3875);
WIRE 17 -1 (-3200 3775)(-3200 3825);
WIRE 17 -1 (-1550 3725)(-1550 3775);
WIRE 17 -1 (-1550 3675)(-1550 3725);
WIRE 17 -1 (-1550 3625)(-1550 3675);
WIRE 17 -1 (-1550 3575)(-1550 3625);
WIRE 17 -1 (-1550 3525)(-1550 3575);
WIRE 17 -1 (-1550 3475)(-1550 3525);
WIRE 17 -1 (-1550 3425)(-1550 3475);
WIRE 17 -1 (-1550 3375)(-1550 3425);
WIRE 17 -1 (-1550 3325)(-1550 3375);
WIRE 17 -1 (-1550 3275)(-1550 3325);
WIRE 17 -1 (-1550 3225)(-1550 3275);
WIRE 17 -1 (-1550 3175)(-1550 3225);
WIRE 17 -1 (-1550 3125)(-1550 3175);
WIRE 17 -1 (-1550 3075)(-1550 3125);
WIRE 17 -1 (-1550 3025)(-1550 3075);
WIRE 17 -1 (-1550 2975)(-1550 3025);
WIRE 17 -1 (-1550 2925)(-1550 2975);
WIRE 17 -1 (-1550 2875)(-1550 2925);
WIRE 17 -1 (-1550 2825)(-1550 2875);
WIRE 17 -1 (-1550 2775)(-1550 2825);
WIRE 17 -1 (-1550 2725)(-1550 2775);
WIRE 17 -1 (-1550 2675)(-1550 2725);
WIRE 17 -1 (-1550 2625)(-1550 2675);
WIRE 17 -1 (-1550 2575)(-1550 2625);
WIRE 17 -1 (-1550 2525)(-1550 2575);
WIRE 17 -1 (-1550 2475)(-1550 2525);
WIRE 17 -1 (-1550 2425)(-1550 2475);
WIRE 17 -1 (-1550 2375)(-1550 2425);
WIRE 17 -1 (-1550 2325)(-1550 2375);
WIRE 17 -1 (-1550 2275)(-1550 2325);
WIRE 17 -1 (-1550 2225)(-1550 2275);
WIRE 17 -1 (-1550 2175)(-1550 2225);
WIRE 17 -1 (-1550 2125)(-1550 2175);
WIRE 17 -1 (-1550 2075)(-1550 2125);
WIRE 17 -1 (-1550 2025)(-1550 2075);
WIRE 17 -1 (-1550 1975)(-1550 2025);
WIRE 17 -1 (-1550 1925)(-1550 1975);
WIRE 17 -1 (-1550 1875)(-1550 1925);
WIRE 17 -1 (-1550 1825)(-1550 1875);
WIRE 17 -1 (-1550 1775)(-1550 1825);
WIRE 17 -1 (-1550 1725)(-1550 1775);
WIRE 17 -1 (-1550 1675)(-1550 1725);
WIRE 17 -1 (-1550 1625)(-1550 1675);
WIRE 17 -1 (-1550 1575)(-1550 1625);
WIRE 17 -1 (-1550 1525)(-1550 1575);
WIRE 17 -1 (-1550 1475)(-1550 1525);
WIRE 17 -1 (-1550 1425)(-1550 1475);
WIRE 17 -1 (-1550 1375)(-1550 1425);
WIRE 17 -1 (-1550 1325)(-1550 1375);
WIRE 17 -1 (-1550 1275)(-1550 1325);
WIRE 17 -1 (-3200 3225)(-3200 3250);
WIRE 17 -1 (-3200 3125)(-3200 3225);
WIRE 17 -1 (-3200 3250)(-3750 3250);
FORCEPROP 2 LAST SIG_NAME M_A_CLK_DP<3:0>
J 0
(-3725 3260);
DISPLAY 0.617021 (-3725 3260);
PAINT ORANGE (-3725 3260);
WIRE 17 -1 (-3200 2525)(-3200 2550);
WIRE 17 -1 (-3200 2475)(-3200 2525);
WIRE 17 -1 (-3200 2550)(-3750 2550);
FORCEPROP 2 LAST SIG_NAME M_A_ODT<3:0>
J 0
(-3725 2560);
DISPLAY 0.617021 (-3725 2560);
PAINT ORANGE (-3725 2560);
WIRE 17 -1 (-3200 2825)(-3200 2875);
WIRE 17 -1 (-3200 2775)(-3200 2825);
WIRE 17 -1 (-3200 2875)(-3200 2925);
WIRE 17 -1 (-3200 2925)(-3200 2950);
WIRE 17 -1 (-3200 2950)(-3750 2950);
FORCEPROP 2 LAST SIG_NAME M_A_CS_N<7:0>
J 0
(-3725 2960);
DISPLAY 0.617021 (-3725 2960);
PAINT ORANGE (-3725 2960);
WIRE 17 -1 (-3200 3425)(-3200 3475);
WIRE 17 -1 (-3200 3500)(-3200 3475);
WIRE 17 -1 (-3200 3500)(-3750 3500);
FORCEPROP 2 LAST SIG_NAME M_A_BA<1:0>
J 0
(-3725 3510);
DISPLAY 0.617021 (-3725 3510);
PAINT ORANGE (-3725 3510);
WIRE 17 -1 (-3400 3175)(-3400 3200);
WIRE 17 -1 (-3400 3175)(-3400 3075);
WIRE 17 -1 (-3400 3200)(-3750 3200);
FORCEPROP 2 LAST SIG_NAME M_A_CLK_DN<3:0>
J 0
(-3725 3210);
DISPLAY 0.617021 (-3725 3210);
PAINT ORANGE (-3725 3210);
WIRE 17 -1 (-3200 3575)(-3200 3625);
WIRE 17 -1 (-3200 3625)(-3200 3675);
WIRE 17 -1 (-3200 3675)(-3200 3725);
WIRE 17 -1 (-3200 3725)(-3200 3775);
WIRE 17 -1 (-3200 2275)(-3200 2325);
WIRE 17 -1 (-3200 2225)(-3200 2275);
WIRE 17 -1 (-3200 2325)(-3200 2375);
WIRE 17 -1 (-3200 2375)(-3200 2400);
WIRE 17 -1 (-3200 2175)(-3200 2225);
WIRE 17 -1 (-3200 2125)(-3200 2175);
WIRE 17 -1 (-3200 2400)(-3750 2400);
FORCEPROP 2 LAST SIG_NAME M_A_ECC<7:0>
J 0
(-3725 2410);
DISPLAY 0.617021 (-3725 2410);
PAINT ORANGE (-3725 2410);
WIRE 17 -1 (-3200 2075)(-3200 2125);
WIRE 17 -1 (-3200 2025)(-3200 2075);
WIRE 17 -1 (-3200 2675)(-3200 2700);
WIRE 17 -1 (-3200 2625)(-3200 2675);
WIRE 17 -1 (-3200 2700)(-3750 2700);
FORCEPROP 2 LAST SIG_NAME M_A_CKE<3:0>
J 0
(-3725 2710);
DISPLAY 0.617021 (-3725 2710);
PAINT ORANGE (-3725 2710);
WIRE 17 -1 (-3200 3325)(-3200 3375);
WIRE 17 -1 (-3200 3375)(-3200 3400);
WIRE 17 -1 (-3200 3400)(-3750 3400);
FORCEPROP 2 LAST SIG_NAME M_A_BG<1:0>
J 0
(-3725 3410);
DISPLAY 0.617021 (-3725 3410);
PAINT ORANGE (-3725 3410);
WIRE 16 -1 (-750 850)(-600 850);
WIRE 16 -1 (-750 850)(-750 900);
WIRE 16 -1 (-750 900)(-600 900);
WIRE 16 -1 (-750 900)(-750 950);
WIRE 16 -1 (-750 950)(-600 950);
WIRE 16 -1 (-750 950)(-750 1000);
WIRE 16 -1 (-750 1000)(-750 1050);
WIRE 16 -1 (-750 1000)(-600 1000);
WIRE 16 -1 (-750 1050)(-600 1050);
WIRE 16 -1 (-750 1050)(-750 1100);
WIRE 16 -1 (-750 1100)(-600 1100);
WIRE 16 -1 (-750 1100)(-750 1150);
WIRE 16 -1 (-750 1150)(-600 1150);
WIRE 16 -1 (-750 1150)(-750 1200);
WIRE 16 -1 (-750 1200)(-600 1200);
WIRE 16 -1 (-750 1200)(-750 1250);
WIRE 16 -1 (-750 1250)(-750 1300);
WIRE 16 -1 (-750 1250)(-600 1250);
WIRE 16 -1 (-750 1300)(-600 1300);
WIRE 16 -1 (-750 1300)(-750 1350);
WIRE 16 -1 (-750 1350)(-600 1350);
WIRE 16 -1 (-750 1350)(-750 1400);
WIRE 16 -1 (-750 1400)(-600 1400);
WIRE 16 -1 (-750 1400)(-750 1450);
WIRE 16 -1 (-750 1450)(-600 1450);
WIRE 16 -1 (-750 1450)(-750 1500);
WIRE 16 -1 (-750 1500)(-750 1550);
WIRE 16 -1 (-750 1500)(-600 1500);
WIRE 16 -1 (-750 1550)(-600 1550);
WIRE 16 -1 (-750 1550)(-750 1600);
WIRE 16 -1 (-750 1600)(-600 1600);
WIRE 16 -1 (-750 1600)(-750 1650);
WIRE 16 -1 (-750 1650)(-600 1650);
WIRE 16 -1 (-750 1650)(-750 1700);
WIRE 16 -1 (-750 1700)(-600 1700);
WIRE 16 -1 (-750 1700)(-750 1750);
WIRE 16 -1 (-750 1750)(-750 1800);
WIRE 16 -1 (-750 1750)(-600 1750);
WIRE 16 -1 (-750 1800)(-600 1800);
WIRE 16 -1 (-750 1800)(-750 1850);
WIRE 16 -1 (-750 1850)(-600 1850);
WIRE 16 -1 (-750 1850)(-750 1900);
WIRE 16 -1 (-750 1900)(-600 1900);
WIRE 16 -1 (-750 1900)(-750 1950);
WIRE 16 -1 (-750 1950)(-600 1950);
WIRE 16 -1 (-750 1950)(-750 2000);
WIRE 16 -1 (-750 2000)(-750 2050);
WIRE 16 -1 (-750 2000)(-600 2000);
WIRE 16 -1 (-750 2050)(-600 2050);
WIRE 16 -1 (-750 2050)(-750 2100);
WIRE 16 -1 (-750 2100)(-600 2100);
WIRE 16 -1 (-1125 2100)(-750 2100);
WIRE 16 -1 (-1125 2200)(-1125 2100);
WIRE 16 -1 (1050 3600)(1250 3600);
WIRE 16 -1 (1050 3550)(1050 3600);
WIRE 16 -1 (1050 3550)(1250 3550);
WIRE 16 -1 (1050 3500)(1050 3550);
WIRE 16 -1 (1050 3500)(1250 3500);
WIRE 16 -1 (1050 3450)(1050 3500);
WIRE 16 -1 (1050 3450)(1250 3450);
WIRE 16 -1 (1050 3400)(1050 3450);
WIRE 16 -1 (1050 3400)(1250 3400);
WIRE 16 -1 (1050 3350)(1050 3400);
WIRE 16 -1 (1050 3350)(1250 3350);
WIRE 16 -1 (1050 3300)(1050 3350);
WIRE 16 -1 (1050 3300)(1250 3300);
WIRE 16 -1 (1050 3250)(1050 3300);
WIRE 16 -1 (1050 3250)(1250 3250);
WIRE 16 -1 (1050 3200)(1050 3250);
WIRE 16 -1 (1050 3200)(1250 3200);
WIRE 16 -1 (1050 3150)(1050 3200);
WIRE 16 -1 (1050 3150)(1250 3150);
WIRE 16 -1 (1050 3100)(1050 3150);
WIRE 16 -1 (1050 3100)(1250 3100);
WIRE 16 -1 (1050 3050)(1050 3100);
WIRE 16 -1 (1050 3050)(1250 3050);
WIRE 16 -1 (1050 3000)(1050 3050);
WIRE 16 -1 (1050 3000)(1250 3000);
WIRE 16 -1 (1050 2950)(1050 3000);
WIRE 16 -1 (1050 2950)(1250 2950);
WIRE 16 -1 (1050 2900)(1050 2950);
WIRE 16 -1 (1050 2900)(1250 2900);
WIRE 16 -1 (1050 2850)(1050 2900);
WIRE 16 -1 (1050 2850)(1250 2850);
WIRE 16 -1 (1050 2800)(1050 2850);
WIRE 16 -1 (1050 2800)(1250 2800);
WIRE 16 -1 (1050 2750)(1050 2800);
WIRE 16 -1 (1050 2750)(1250 2750);
WIRE 16 -1 (1050 2700)(1050 2750);
WIRE 16 -1 (1050 2700)(1250 2700);
WIRE 16 -1 (1050 2650)(1050 2700);
WIRE 16 -1 (1050 2650)(1250 2650);
WIRE 16 -1 (1050 2600)(1050 2650);
WIRE 16 -1 (1050 2600)(1250 2600);
WIRE 16 -1 (1050 2550)(1050 2600);
WIRE 16 -1 (1050 2550)(1250 2550);
WIRE 16 -1 (1050 2500)(1050 2550);
WIRE 16 -1 (1050 2500)(1250 2500);
WIRE 16 -1 (1050 2450)(1050 2500);
WIRE 16 -1 (1050 2450)(1250 2450);
WIRE 16 -1 (1050 2400)(1050 2450);
WIRE 16 -1 (1050 2400)(1250 2400);
WIRE 16 -1 (1050 2350)(1050 2400);
WIRE 16 -1 (1050 2350)(1250 2350);
WIRE 16 -1 (1050 2300)(1050 2350);
WIRE 16 -1 (1050 2300)(1250 2300);
WIRE 16 -1 (1050 2250)(1050 2300);
WIRE 16 -1 (1050 2250)(1250 2250);
WIRE 16 -1 (1050 2200)(1050 2250);
WIRE 16 -1 (1050 2200)(1250 2200);
WIRE 16 -1 (1050 2150)(1050 2200);
WIRE 16 -1 (1050 2150)(1250 2150);
WIRE 16 -1 (1050 2100)(1050 2150);
WIRE 16 -1 (1050 2100)(1250 2100);
WIRE 16 -1 (1050 2050)(1050 2100);
WIRE 16 -1 (1050 2050)(1250 2050);
WIRE 16 -1 (1050 2000)(1050 2050);
WIRE 16 -1 (1050 2000)(1250 2000);
WIRE 16 -1 (1050 1950)(1050 2000);
WIRE 16 -1 (1050 1950)(1250 1950);
WIRE 16 -1 (1050 1900)(1050 1950);
WIRE 16 -1 (1050 1900)(1250 1900);
WIRE 16 -1 (1050 1850)(1050 1900);
WIRE 16 -1 (1050 1850)(1250 1850);
WIRE 16 -1 (1050 1800)(1050 1850);
WIRE 16 -1 (1050 1800)(1250 1800);
WIRE 16 -1 (1050 1750)(1050 1800);
WIRE 16 -1 (1050 1750)(1250 1750);
WIRE 16 -1 (1050 1700)(1050 1750);
WIRE 16 -1 (1050 1700)(1250 1700);
WIRE 16 -1 (1050 1650)(1050 1700);
WIRE 16 -1 (1050 1650)(1250 1650);
WIRE 16 -1 (1050 1600)(1050 1650);
WIRE 16 -1 (1050 1600)(1250 1600);
WIRE 16 -1 (1050 1550)(1050 1600);
WIRE 16 -1 (1050 1550)(1250 1550);
WIRE 16 -1 (1050 1500)(1050 1550);
WIRE 16 -1 (1050 1500)(1250 1500);
WIRE 16 -1 (1050 1450)(1050 1500);
WIRE 16 -1 (1050 1450)(1250 1450);
WIRE 16 -1 (1050 1400)(1050 1450);
WIRE 16 -1 (1050 1400)(1250 1400);
WIRE 16 -1 (1050 1350)(1050 1400);
WIRE 16 -1 (1050 1350)(1250 1350);
WIRE 16 -1 (1050 1300)(1050 1350);
WIRE 16 -1 (1050 1300)(1250 1300);
WIRE 16 -1 (1050 1200)(1050 1300);
WIRE 16 -1 (2450 3600)(2250 3600);
WIRE 16 -1 (2450 3550)(2450 3600);
WIRE 16 -1 (2450 3500)(2450 3550);
WIRE 16 -1 (2450 3550)(2250 3550);
WIRE 16 -1 (2450 3450)(2450 3500);
WIRE 16 -1 (2450 3500)(2250 3500);
WIRE 16 -1 (2450 3400)(2450 3450);
WIRE 16 -1 (2450 3450)(2250 3450);
WIRE 16 -1 (2450 3350)(2450 3400);
WIRE 16 -1 (2450 3400)(2250 3400);
WIRE 16 -1 (2450 3300)(2450 3350);
WIRE 16 -1 (2450 3350)(2250 3350);
WIRE 16 -1 (2450 3250)(2450 3300);
WIRE 16 -1 (2450 3300)(2250 3300);
WIRE 16 -1 (2450 3200)(2450 3250);
WIRE 16 -1 (2450 3250)(2250 3250);
WIRE 16 -1 (2450 3150)(2450 3200);
WIRE 16 -1 (2450 3200)(2250 3200);
WIRE 16 -1 (2450 3100)(2450 3150);
WIRE 16 -1 (2450 3150)(2250 3150);
WIRE 16 -1 (2450 3100)(2250 3100);
WIRE 16 -1 (2450 3050)(2450 3100);
WIRE 16 -1 (2450 3000)(2450 3050);
WIRE 16 -1 (2450 3050)(2250 3050);
WIRE 16 -1 (2450 2950)(2450 3000);
WIRE 16 -1 (2450 3000)(2250 3000);
WIRE 16 -1 (2450 2900)(2450 2950);
WIRE 16 -1 (2450 2950)(2250 2950);
WIRE 16 -1 (2450 2850)(2450 2900);
WIRE 16 -1 (2450 2900)(2250 2900);
WIRE 16 -1 (2450 2800)(2450 2850);
WIRE 16 -1 (2450 2850)(2250 2850);
WIRE 16 -1 (2450 2750)(2450 2800);
WIRE 16 -1 (2450 2800)(2250 2800);
WIRE 16 -1 (2450 2700)(2450 2750);
WIRE 16 -1 (2450 2750)(2250 2750);
WIRE 16 -1 (2450 2650)(2450 2700);
WIRE 16 -1 (2450 2700)(2250 2700);
WIRE 16 -1 (2450 2600)(2450 2650);
WIRE 16 -1 (2450 2650)(2250 2650);
WIRE 16 -1 (2450 2600)(2250 2600);
WIRE 16 -1 (2450 2550)(2450 2600);
WIRE 16 -1 (2450 2500)(2450 2550);
WIRE 16 -1 (2450 2550)(2250 2550);
WIRE 16 -1 (2450 2450)(2450 2500);
WIRE 16 -1 (2450 2500)(2250 2500);
WIRE 16 -1 (2450 2400)(2450 2450);
WIRE 16 -1 (2450 2450)(2250 2450);
WIRE 16 -1 (2450 2350)(2450 2400);
WIRE 16 -1 (2450 2400)(2250 2400);
WIRE 16 -1 (2450 2300)(2450 2350);
WIRE 16 -1 (2450 2350)(2250 2350);
WIRE 16 -1 (2450 2250)(2450 2300);
WIRE 16 -1 (2450 2300)(2250 2300);
WIRE 16 -1 (2450 2200)(2450 2250);
WIRE 16 -1 (2450 2250)(2250 2250);
WIRE 16 -1 (2450 2150)(2450 2200);
WIRE 16 -1 (2450 2200)(2250 2200);
WIRE 16 -1 (2450 2100)(2450 2150);
WIRE 16 -1 (2450 2150)(2250 2150);
WIRE 16 -1 (2450 2050)(2450 2100);
WIRE 16 -1 (2450 2100)(2250 2100);
WIRE 16 -1 (2450 2050)(2250 2050);
WIRE 16 -1 (2450 2000)(2450 2050);
WIRE 16 -1 (2450 1950)(2450 2000);
WIRE 16 -1 (2450 2000)(2250 2000);
WIRE 16 -1 (2450 1900)(2450 1950);
WIRE 16 -1 (2450 1950)(2250 1950);
WIRE 16 -1 (2450 1850)(2450 1900);
WIRE 16 -1 (2450 1900)(2250 1900);
WIRE 16 -1 (2450 1800)(2450 1850);
WIRE 16 -1 (2450 1850)(2250 1850);
WIRE 16 -1 (2450 1750)(2450 1800);
WIRE 16 -1 (2450 1800)(2250 1800);
WIRE 16 -1 (2450 1700)(2450 1750);
WIRE 16 -1 (2450 1750)(2250 1750);
WIRE 16 -1 (2450 1650)(2450 1700);
WIRE 16 -1 (2450 1700)(2250 1700);
WIRE 16 -1 (2450 1600)(2450 1650);
WIRE 16 -1 (2450 1650)(2250 1650);
WIRE 16 -1 (2450 1550)(2450 1600);
WIRE 16 -1 (2450 1600)(2250 1600);
WIRE 16 -1 (2450 1550)(2250 1550);
WIRE 16 -1 (2450 1500)(2450 1550);
WIRE 16 -1 (2450 1450)(2450 1500);
WIRE 16 -1 (2450 1500)(2250 1500);
WIRE 16 -1 (2450 1400)(2450 1450);
WIRE 16 -1 (2450 1450)(2250 1450);
WIRE 16 -1 (2450 1350)(2450 1400);
WIRE 16 -1 (2450 1400)(2250 1400);
WIRE 16 -1 (2450 1300)(2450 1350);
WIRE 16 -1 (2450 1350)(2250 1350);
WIRE 16 -1 (2450 1200)(2450 1300);
WIRE 16 -1 (2450 1300)(2250 1300);
WIRE 16 -1 (-3100 1450)(-2900 1450);
WIRE 16 -1 (-3100 1450)(-3100 1500);
WIRE 16 -1 (-3100 1500)(-2900 1500);
WIRE 16 -1 (-3100 1550)(-3100 1500);
WIRE 16 -1 (-2900 1550)(-3100 1550);
WIRE 16 -1 (-3100 1550)(-5050 1550);
WIRE 16 -1 (-5050 1550)(-5050 1450);
WIRE 16 -1 (-4350 950)(-4350 850);
WIRE 16 -1 (-750 2350)(-600 2350);
WIRE 16 -1 (-750 2350)(-750 2400);
WIRE 16 -1 (-750 2400)(-600 2400);
WIRE 16 -1 (-750 2400)(-750 2450);
WIRE 16 -1 (-750 2450)(-600 2450);
WIRE 16 -1 (-750 2450)(-750 2500);
WIRE 16 -1 (-750 2500)(-600 2500);
WIRE 16 -1 (-750 2550)(-750 2500);
WIRE 16 -1 (-750 2650)(-750 2550);
WIRE 16 -1 (-750 2550)(-600 2550);
WIRE 16 -1 (-2900 1600)(-5050 1600);
WIRE 16 -1 (-5050 1700)(-5050 1600);
WIRE 16 -1 (-600 2200)(-750 2200);
WIRE 16 -1 (-750 2200)(-750 2250);
WIRE 16 -1 (-750 2250)(-600 2250);
WIRE 16 -1 (-900 2250)(-750 2250);
WIRE 16 -1 (-900 2250)(-900 2350);
WIRE 16 -1 (400 2500)(600 2500);
WIRE 16 -1 (600 2500)(600 2550);
WIRE 16 -1 (400 2550)(600 2550);
WIRE 16 -1 (600 2550)(600 2725);
WIRE 16 -1 (-4350 1150)(-4350 1250);
WIRE 16 -1 (-2900 1250)(-4350 1250);
FORCEPROP 2 LAST SIG_NAME M_A_VREF
J 0
(-3700 1260);
DISPLAY 0.617021 (-3700 1260);
PAINT ORANGE (-3700 1260);
WIRE 16 -1 (-4450 1250)(-4350 1250);
WIRE 16 -1 (-3750 1100)(-2900 1100);
FORCEPROP 2 LAST SIG_NAME TP_CH_A_DIMM_A0_RFU_1
J 0
(-3700 1110);
DISPLAY 0.617021 (-3700 1110);
PAINT ORANGE (-3700 1110);
FORCEPROP 2 LASTPROP $XRERR UNIQUE?
J 0
(-3990 1100);
DISPLAY 0.638298 (-3990 1100);
PAINT MONO (-3990 1100);
DISPLAY INVISIBLE (-3990 1100);
WIRE 16 -1 (-3750 1050)(-2900 1050);
FORCEPROP 2 LAST SIG_NAME TP_CH_A_DIMM_A0_RFU_0
J 0
(-3700 1060);
DISPLAY 0.617021 (-3700 1060);
PAINT ORANGE (-3700 1060);
FORCEPROP 2 LASTPROP $XRERR UNIQUE?
J 0
(-3990 1050);
DISPLAY 0.638298 (-3990 1050);
PAINT MONO (-3990 1050);
DISPLAY INVISIBLE (-3990 1050);
WIRE 16 -1 (-3750 1150)(-2900 1150);
FORCEPROP 2 LAST SIG_NAME TP_CH_A_DIMM_A0_RFU_2
J 0
(-3700 1160);
DISPLAY 0.617021 (-3700 1160);
PAINT ORANGE (-3700 1160);
FORCEPROP 2 LASTPROP $XRERR UNIQUE?
J 0
(-3990 1150);
DISPLAY 0.638298 (-3990 1150);
PAINT MONO (-3990 1150);
DISPLAY INVISIBLE (-3990 1150);
WIRE 16 -1 (-2900 2000)(-3100 2000);
WIRE 16 -1 (-3750 1350)(-2900 1350);
FORCEPROP 2 LAST SIG_NAME SMB_DDR_ABC_VPP_SCL
J 0
(-3710 1360);
DISPLAY 0.617021 (-3710 1360);
PAINT ORANGE (-3710 1360);
WIRE 16 -1 (-2900 1400)(-3750 1400);
WIRE 16 -1 (-3750 950)(-2900 950);
FORCEPROP 2 LAST SIG_NAME FM_ADR_COMPLETE_ABC_N
J 0
(-3700 960);
DISPLAY 0.617021 (-3700 960);
PAINT ORANGE (-3700 960);
WIRE 16 -1 (-2900 1750)(-3975 1750);
FORCEPROP 2 LAST SIG_NAME M_A_ALERT_N
J 0
(-3925 1760);
DISPLAY 0.617021 (-3925 1760);
PAINT ORANGE (-3925 1760);
WIRE 16 -1 (-2900 1700)(-3975 1700);
FORCEPROP 2 LAST SIG_NAME M_A_ACT_N
J 0
(-3925 1710);
DISPLAY 0.617021 (-3925 1710);
PAINT ORANGE (-3925 1710);
WIRE 16 -1 (-3300 2300)(-3750 2300);
FORCEPROP 2 LAST SIG_NAME M_ABC_RST_N
J 0
(-3725 2310);
DISPLAY 0.617021 (-3725 2310);
PAINT ORANGE (-3725 2310);
WIRE 16 -1 (-3300 1850)(-3300 2300);
WIRE 16 -1 (-2900 1850)(-3300 1850);
WIRE 16 -1 (-3350 2050)(-3975 2050);
FORCEPROP 2 LAST SIG_NAME FM_DIMM_EVENT_COD_N
J 0
(-3903 2058);
DISPLAY 0.617021 (-3903 2058);
PAINT ORANGE (-3903 2058);
WIRE 16 -1 (-3350 1800)(-3350 2050);
WIRE 16 -1 (-3350 1800)(-2900 1800);
WIRE 16 -1 (-3250 2350)(-3750 2350);
FORCEPROP 2 LAST SIG_NAME M_A_PAR
J 0
(-3725 2360);
DISPLAY 0.617021 (-3725 2360);
PAINT ORANGE (-3725 2360);
WIRE 16 -1 (-3250 1900)(-3250 2350);
WIRE 16 -1 (-2900 1900)(-3250 1900);
WIRE 16 -1 (-2900 2750)(-3100 2750);
WIRE 16 -1 (-2900 2600)(-3100 2600);
WIRE 16 -1 (-2900 2450)(-3100 2450);
WIRE 16 -1 (-2900 2350)(-3100 2350);
WIRE 16 -1 (-2900 4050)(-3100 4050);
WIRE 16 -1 (-2900 3650)(-3100 3650);
WIRE 16 -1 (-2900 3400)(-3100 3400);
WIRE 16 -1 (-2900 3350)(-3100 3350);
WIRE 16 -1 (-2900 3300)(-3100 3300);
WIRE 16 -1 (-2900 2650)(-3100 2650);
WIRE 16 -1 (-2900 3050)(-3300 3050);
WIRE 16 -1 (-2900 2050)(-3100 2050);
WIRE 16 -1 (-2900 2100)(-3100 2100);
WIRE 16 -1 (-2900 2150)(-3100 2150);
WIRE 16 -1 (-2900 2200)(-3100 2200);
WIRE 16 -1 (-2900 2250)(-3100 2250);
WIRE 16 -1 (-2900 2300)(-3100 2300);
WIRE 16 -1 (-2900 4000)(-3100 4000);
WIRE 16 -1 (-2900 3950)(-3100 3950);
WIRE 16 -1 (-2900 3900)(-3100 3900);
WIRE 16 -1 (-2900 3850)(-3100 3850);
WIRE 16 -1 (-2900 3800)(-3100 3800);
WIRE 16 -1 (-2900 3750)(-3100 3750);
WIRE 16 -1 (-2900 3700)(-3100 3700);
WIRE 16 -1 (-2900 3600)(-3100 3600);
WIRE 16 -1 (-2900 3550)(-3100 3550);
WIRE 16 -1 (-2900 2850)(-3100 2850);
WIRE 16 -1 (-2900 2900)(-3100 2900);
WIRE 16 -1 (-2900 3100)(-3100 3100);
WIRE 16 -1 (-2900 3150)(-3300 3150);
WIRE 16 -1 (-2900 3450)(-3100 3450);
WIRE 16 -1 (-2900 2800)(-3100 2800);
WIRE 16 -1 (-2900 2500)(-3100 2500);
WIRE 16 -1 (-2900 3200)(-3100 3200);
WIRE 16 -1 (-3050 2950)(-2900 2950);
WIRE 16 -1 (-3050 3000)(-3050 2950);
WIRE 16 -1 (-3050 3000)(-3750 3000);
FORCEPROP 2 LAST SIG_NAME M_A_C<2>
J 0
(-3700 3010);
DISPLAY 0.617021 (-3700 3010);
PAINT ORANGE (-3700 3010);
WIRE 16 -1 (-1650 1500)(-1900 1500);
WIRE 16 -1 (-1650 1450)(-1900 1450);
WIRE 16 -1 (-1650 1400)(-1900 1400);
WIRE 16 -1 (-1650 1350)(-1900 1350);
WIRE 16 -1 (-1650 1250)(-1900 1250);
WIRE 16 -1 (-1650 1300)(-1900 1300);
WIRE 16 -1 (-1650 2000)(-1900 2000);
WIRE 16 -1 (-1650 1550)(-1900 1550);
WIRE 16 -1 (-1650 1600)(-1900 1600);
WIRE 16 -1 (-1650 1700)(-1900 1700);
WIRE 16 -1 (-1650 1750)(-1900 1750);
WIRE 16 -1 (-1650 1800)(-1900 1800);
WIRE 16 -1 (-1650 1850)(-1900 1850);
WIRE 16 -1 (-1650 1900)(-1900 1900);
WIRE 16 -1 (-1650 1950)(-1900 1950);
WIRE 16 -1 (-1650 1650)(-1900 1650);
WIRE 16 -1 (-1650 2100)(-1900 2100);
WIRE 16 -1 (-1650 2550)(-1900 2550);
WIRE 16 -1 (-1650 2050)(-1900 2050);
WIRE 16 -1 (-1650 2150)(-1900 2150);
WIRE 16 -1 (-1650 2200)(-1900 2200);
WIRE 16 -1 (-1650 2300)(-1900 2300);
WIRE 16 -1 (-1650 2350)(-1900 2350);
WIRE 16 -1 (-1650 2450)(-1900 2450);
WIRE 16 -1 (-1650 2500)(-1900 2500);
WIRE 16 -1 (-1650 2400)(-1900 2400);
WIRE 16 -1 (-1650 2250)(-1900 2250);
WIRE 16 -1 (-1650 3050)(-1900 3050);
WIRE 16 -1 (-1650 3000)(-1900 3000);
WIRE 16 -1 (-1650 2800)(-1900 2800);
WIRE 16 -1 (-1650 2600)(-1900 2600);
WIRE 16 -1 (-1650 2650)(-1900 2650);
WIRE 16 -1 (-1650 2750)(-1900 2750);
WIRE 16 -1 (-1650 2850)(-1900 2850);
WIRE 16 -1 (-1650 2950)(-1900 2950);
WIRE 16 -1 (-1650 2900)(-1900 2900);
WIRE 16 -1 (-1650 2700)(-1900 2700);
WIRE 16 -1 (-1650 3150)(-1900 3150);
WIRE 16 -1 (-1650 3100)(-1900 3100);
WIRE 16 -1 (-1650 3200)(-1900 3200);
WIRE 16 -1 (-1650 3250)(-1900 3250);
WIRE 16 -1 (-1650 3350)(-1900 3350);
WIRE 16 -1 (-1650 3400)(-1900 3400);
WIRE 16 -1 (-1650 3450)(-1900 3450);
WIRE 16 -1 (-1650 3500)(-1900 3500);
WIRE 16 -1 (-1650 3550)(-1900 3550);
WIRE 16 -1 (-1650 3300)(-1900 3300);
WIRE 16 -1 (-1650 3600)(-1900 3600);
WIRE 16 -1 (-1650 3650)(-1900 3650);
WIRE 16 -1 (-1650 3700)(-1900 3700);
WIRE 16 -1 (-1650 3750)(-1900 3750);
WIRE 16 -1 (-1650 3900)(-1900 3900);
WIRE 16 -1 (-1650 3950)(-1900 3950);
WIRE 16 -1 (-1650 4000)(-1900 4000);
WIRE 16 -1 (-1650 4050)(-1900 4050);
WIRE 16 -1 (-1650 3850)(-1900 3850);
WIRE 16 -1 (-1650 3800)(-1900 3800);
WIRE 16 -1 (-2900 4350)(-3100 4350);
WIRE 16 -1 (-2900 4300)(-3100 4300);
WIRE 16 -1 (-2900 4250)(-3100 4250);
WIRE 16 -1 (-2900 4100)(-3100 4100);
WIRE 16 -1 (-2900 4400)(-3100 4400);
WIRE 16 -1 (-2900 4200)(-3100 4200);
WIRE 16 -1 (-2900 4150)(-3100 4150);
WIRE 16 -1 (-1650 4400)(-1900 4400);
WIRE 16 -1 (-1650 4350)(-1900 4350);
WIRE 16 -1 (-1650 4300)(-1900 4300);
WIRE 16 -1 (-1650 4150)(-1900 4150);
WIRE 16 -1 (-1650 4100)(-1900 4100);
WIRE 16 -1 (-1650 4200)(-1900 4200);
WIRE 16 -1 (-1650 4250)(-1900 4250);
WIRE 16 -1 (800 4050)(400 4050);
WIRE 16 -1 (600 4000)(400 4000);
WIRE 16 -1 (800 3950)(400 3950);
WIRE 16 -1 (600 3900)(400 3900);
WIRE 16 -1 (800 3850)(400 3850);
WIRE 16 -1 (600 3800)(400 3800);
WIRE 16 -1 (800 3750)(400 3750);
WIRE 16 -1 (600 3700)(400 3700);
WIRE 16 -1 (800 3650)(400 3650);
WIRE 16 -1 (600 3600)(400 3600);
WIRE 16 -1 (800 3550)(400 3550);
WIRE 16 -1 (600 3500)(400 3500);
WIRE 16 -1 (800 3450)(400 3450);
WIRE 16 -1 (600 3400)(400 3400);
WIRE 16 -1 (800 3350)(400 3350);
WIRE 16 -1 (600 3300)(400 3300);
WIRE 16 -1 (800 3250)(400 3250);
WIRE 16 -1 (600 3200)(400 3200);
WIRE 16 -1 (800 3150)(400 3150);
WIRE 16 -1 (600 4900)(400 4900);
WIRE 16 -1 (600 4100)(400 4100);
WIRE 16 -1 (800 4850)(400 4850);
WIRE 16 -1 (600 4800)(400 4800);
WIRE 16 -1 (800 4750)(400 4750);
WIRE 16 -1 (600 4700)(400 4700);
WIRE 16 -1 (800 4650)(400 4650);
WIRE 16 -1 (600 4600)(400 4600);
WIRE 16 -1 (800 4550)(400 4550);
WIRE 16 -1 (600 4500)(400 4500);
WIRE 16 -1 (800 4450)(400 4450);
WIRE 16 -1 (600 4400)(400 4400);
WIRE 16 -1 (800 4350)(400 4350);
WIRE 16 -1 (600 4300)(400 4300);
WIRE 16 -1 (800 4250)(400 4250);
WIRE 16 -1 (600 4200)(400 4200);
WIRE 16 -1 (800 4150)(400 4150);
DOT 1 (-750 1750);
DOT 1 (2450 3550);
DOT 1 (-4350 1250);
DOT 1 (-750 1900);
DOT 1 (-750 2000);
DOT 1 (-750 2050);
DOT 1 (-750 2500);
DOT 1 (-750 1000);
DOT 1 (-750 1300);
DOT 1 (-3100 1500);
DOT 1 (1050 2500);
DOT 1 (1050 2800);
DOT 1 (-750 2400);
DOT 1 (-750 2550);
DOT 1 (2450 1350);
DOT 1 (-750 2250);
DOT 1 (1050 1500);
DOT 1 (1050 1550);
DOT 1 (-750 900);
DOT 1 (-750 950);
DOT 1 (-750 1050);
DOT 1 (-750 1100);
DOT 1 (-750 1250);
DOT 1 (-750 1400);
DOT 1 (-750 1450);
DOT 1 (-750 1500);
DOT 1 (-750 1550);
DOT 1 (-750 1600);
DOT 1 (-750 1650);
DOT 1 (-750 1700);
DOT 1 (-750 1800);
DOT 1 (-750 1850);
DOT 1 (1050 1300);
DOT 1 (1050 1350);
DOT 1 (1050 1400);
DOT 1 (1050 1450);
DOT 1 (1050 1600);
DOT 1 (1050 1650);
DOT 1 (1050 1700);
DOT 1 (1050 1800);
DOT 1 (1050 1750);
DOT 1 (1050 1850);
DOT 1 (1050 1900);
DOT 1 (1050 1950);
DOT 1 (1050 2000);
DOT 1 (1050 2100);
DOT 1 (1050 2300);
DOT 1 (1050 2450);
DOT 1 (1050 2400);
DOT 1 (1050 2600);
DOT 1 (1050 2700);
DOT 1 (1050 2650);
DOT 1 (1050 2750);
DOT 1 (1050 2850);
DOT 1 (1050 2950);
DOT 1 (1050 2900);
DOT 1 (1050 3050);
DOT 1 (1050 3000);
DOT 1 (1050 3100);
DOT 1 (1050 3150);
DOT 1 (1050 3350);
DOT 1 (1050 3300);
DOT 1 (1050 3250);
DOT 1 (1050 3400);
DOT 1 (1050 3450);
DOT 1 (1050 3500);
DOT 1 (1050 3550);
DOT 1 (2450 1300);
DOT 1 (2450 1400);
DOT 1 (2450 1450);
DOT 1 (2450 1500);
DOT 1 (2450 1550);
DOT 1 (2450 1600);
DOT 1 (2450 1650);
DOT 1 (2450 1700);
DOT 1 (2450 1800);
DOT 1 (2450 1750);
DOT 1 (2450 1850);
DOT 1 (2450 1900);
DOT 1 (2450 1950);
DOT 1 (2450 2050);
DOT 1 (2450 2000);
DOT 1 (2450 2150);
DOT 1 (2450 2200);
DOT 1 (2450 2100);
DOT 1 (2450 2250);
DOT 1 (2450 2300);
DOT 1 (2450 2400);
DOT 1 (2450 2450);
DOT 1 (2450 2350);
DOT 1 (2450 2500);
DOT 1 (2450 2550);
DOT 1 (2450 2600);
DOT 1 (2450 2700);
DOT 1 (2450 2650);
DOT 1 (2450 2750);
DOT 1 (2450 2800);
DOT 1 (2450 2850);
DOT 1 (2450 2950);
DOT 1 (2450 2900);
DOT 1 (2450 3050);
DOT 1 (2450 3000);
DOT 1 (2450 3100);
DOT 1 (2450 3150);
DOT 1 (2450 3200);
DOT 1 (2450 3300);
DOT 1 (2450 3350);
DOT 1 (2450 3250);
DOT 1 (2450 3400);
DOT 1 (2450 3450);
DOT 1 (2450 3500);
DOT 1 (1050 2150);
DOT 1 (1050 2200);
DOT 1 (1050 2250);
DOT 1 (1050 2350);
DOT 1 (600 2550);
DOT 1 (1050 2050);
DOT 1 (1050 2550);
DOT 1 (-750 2100);
DOT 1 (-750 2450);
DOT 1 (-750 1350);
DOT 1 (-750 1150);
DOT 1 (-750 1200);
DOT 1 (-3100 1550);
DOT 1 (1050 3200);
DOT 1 (-750 1950);
FORCENOTE
SMBUS ADDR: 0XA0
(-5300 525) 0;
DISPLAY LEFT (-5300 525);
DISPLAY 1.361702 (-5300 525);
PAINT PURPLE (-5300 525);
FORCENOTE
ROOM = DDR4_CH_A
(-5300 425) 0;
DISPLAY LEFT (-5300 425);
DISPLAY 1.361702 (-5300 425);
PAINT PURPLE (-5300 425);
FORCENOTE
PLACE CAP NEAR DIMM CONNECTOR
(-4304 800) 0;
DISPLAY LEFT (-4304 800);
DISPLAY 1.021277 (-4304 800);
PAINT PURPLE (-4304 800);
QUIT
